(kicad_sch
	(version 20250114)
	(generator "eeschema")
	(generator_version "9.0")
	(paper "A3")
	(title_block
		(title "PolarFire SoM")
		(date "2025-07-22")
		(rev "1.1.4")
		(company "Antmicro Ltd")
		(comment 1 "www.antmicro.com")
	)
	(bus_alias "LPDDR4"
		(members "DQ[0..31]" "DMI[0..3]" "RESET_n" "CS0_A" "CKE0_A" "CK_P" "ODT_CA_A"
			"CK_N" "DQS0_P" "DQS0_N" "DQS1_P" "DQS1_N" "DQS2_P" "DQS2_N" "DQS3_P"
			"DQS3_N" "CA0_A" "CA1_A" "CA2_A" "CA3_A" "CA4_A" "CA5_A"
		)
	)
	(text "Decoupling capacitors"
		(exclude_from_sim no)
		(at 162.56 168.91 0)
		(effects
			(font
				(size 4 4)
				(thickness 0.8)
				(bold yes)
			)
			(justify left bottom)
		)
	)
	(text "VDDQ"
		(exclude_from_sim no)
		(at 246.38 179.07 0)
		(effects
			(font
				(size 2 2)
				(thickness 0.8)
				(bold yes)
			)
			(justify left bottom)
		)
	)
	(text "VDD1"
		(exclude_from_sim no)
		(at 138.43 179.07 0)
		(effects
			(font
				(size 2 2)
				(thickness 0.8)
				(bold yes)
			)
			(justify left bottom)
		)
	)
	(text "LPDDR4"
		(exclude_from_sim no)
		(at 14.605 22.225 0)
		(effects
			(font
				(size 4 4)
				(thickness 0.8)
				(bold yes)
			)
			(justify left bottom)
		)
	)
	(text "VDD2"
		(exclude_from_sim no)
		(at 190.5 179.07 0)
		(effects
			(font
				(size 2 2)
				(thickness 0.8)
				(bold yes)
			)
			(justify left bottom)
		)
	)
	(junction
		(at 246.38 217.17)
		(diameter 0)
		(color 0 0 0 0)
	)
	(junction
		(at 254 217.17)
		(diameter 0)
		(color 0 0 0 0)
	)
	(junction
		(at 238.76 209.55)
		(diameter 0)
		(color 0 0 0 0)
	)
	(junction
		(at 154.94 236.22)
		(diameter 0)
		(color 0 0 0 0)
	)
	(junction
		(at 254 209.55)
		(diameter 0)
		(color 0 0 0 0)
	)
	(junction
		(at 270.51 195.58)
		(diameter 0)
		(color 0 0 0 0)
	)
	(junction
		(at 147.32 187.96)
		(diameter 0)
		(color 0 0 0 0)
	)
	(junction
		(at 196.85 195.58)
		(diameter 0)
		(color 0 0 0 0)
	)
	(junction
		(at 261.62 217.17)
		(diameter 0)
		(color 0 0 0 0)
	)
	(junction
		(at 196.85 187.96)
		(diameter 0)
		(color 0 0 0 0)
	)
	(junction
		(at 154.94 195.58)
		(diameter 0)
		(color 0 0 0 0)
	)
	(junction
		(at 246.38 209.55)
		(diameter 0)
		(color 0 0 0 0)
	)
	(junction
		(at 196.85 217.17)
		(diameter 0)
		(color 0 0 0 0)
	)
	(junction
		(at 261.62 209.55)
		(diameter 0)
		(color 0 0 0 0)
	)
	(junction
		(at 196.85 209.55)
		(diameter 0)
		(color 0 0 0 0)
	)
	(junction
		(at 269.24 217.17)
		(diameter 0)
		(color 0 0 0 0)
	)
	(junction
		(at 204.47 209.55)
		(diameter 0)
		(color 0 0 0 0)
	)
	(junction
		(at 196.85 236.22)
		(diameter 0)
		(color 0 0 0 0)
	)
	(junction
		(at 147.32 228.6)
		(diameter 0)
		(color 0 0 0 0)
	)
	(junction
		(at 212.09 236.22)
		(diameter 0)
		(color 0 0 0 0)
	)
	(junction
		(at 219.71 63.5)
		(diameter 0)
		(color 0 0 0 0)
	)
	(junction
		(at 255.27 187.96)
		(diameter 0)
		(color 0 0 0 0)
	)
	(junction
		(at 196.85 228.6)
		(diameter 0)
		(color 0 0 0 0)
	)
	(junction
		(at 247.65 187.96)
		(diameter 0)
		(color 0 0 0 0)
	)
	(junction
		(at 204.47 236.22)
		(diameter 0)
		(color 0 0 0 0)
	)
	(junction
		(at 187.96 187.96)
		(diameter 0)
		(color 0 0 0 0)
	)
	(junction
		(at 212.09 195.58)
		(diameter 0)
		(color 0 0 0 0)
	)
	(junction
		(at 212.09 217.17)
		(diameter 0)
		(color 0 0 0 0)
	)
	(junction
		(at 262.89 195.58)
		(diameter 0)
		(color 0 0 0 0)
	)
	(junction
		(at 255.27 195.58)
		(diameter 0)
		(color 0 0 0 0)
	)
	(junction
		(at 114.3 99.06)
		(diameter 0)
		(color 0 0 0 0)
	)
	(junction
		(at 154.94 217.17)
		(diameter 0)
		(color 0 0 0 0)
	)
	(junction
		(at 189.23 228.6)
		(diameter 0)
		(color 0 0 0 0)
	)
	(junction
		(at 115.57 63.5)
		(diameter 0)
		(color 0 0 0 0)
	)
	(junction
		(at 204.47 228.6)
		(diameter 0)
		(color 0 0 0 0)
	)
	(junction
		(at 204.47 187.96)
		(diameter 0)
		(color 0 0 0 0)
	)
	(junction
		(at 204.47 217.17)
		(diameter 0)
		(color 0 0 0 0)
	)
	(junction
		(at 147.32 209.55)
		(diameter 0)
		(color 0 0 0 0)
	)
	(junction
		(at 189.23 209.55)
		(diameter 0)
		(color 0 0 0 0)
	)
	(junction
		(at 204.47 195.58)
		(diameter 0)
		(color 0 0 0 0)
	)
	(junction
		(at 262.89 187.96)
		(diameter 0)
		(color 0 0 0 0)
	)
	(bus_entry
		(at 278.13 60.96)
		(size -2.54 2.54)
		(stroke
			(width 0)
			(type default)
		)
	)
	(bus_entry
		(at 99.06 81.28)
		(size 2.54 2.54)
		(stroke
			(width 0)
			(type default)
		)
	)
	(bus_entry
		(at 99.06 93.98)
		(size 2.54 2.54)
		(stroke
			(width 0)
			(type default)
		)
	)
	(bus_entry
		(at 278.13 88.9)
		(size -2.54 2.54)
		(stroke
			(width 0)
			(type default)
		)
	)
	(bus_entry
		(at 99.06 88.9)
		(size 2.54 2.54)
		(stroke
			(width 0)
			(type default)
		)
	)
	(bus_entry
		(at 173.99 86.36)
		(size -2.54 2.54)
		(stroke
			(width 0)
			(type default)
		)
	)
	(bus_entry
		(at 204.47 93.98)
		(size 2.54 2.54)
		(stroke
			(width 0)
			(type default)
		)
	)
	(bus_entry
		(at 173.99 63.5)
		(size -2.54 2.54)
		(stroke
			(width 0)
			(type default)
		)
	)
	(bus_entry
		(at 173.99 71.12)
		(size -2.54 2.54)
		(stroke
			(width 0)
			(type default)
		)
	)
	(bus_entry
		(at 173.99 109.22)
		(size -2.54 2.54)
		(stroke
			(width 0)
			(type default)
		)
	)
	(bus_entry
		(at 173.99 101.6)
		(size -2.54 2.54)
		(stroke
			(width 0)
			(type default)
		)
	)
	(bus_entry
		(at 204.47 73.66)
		(size 2.54 2.54)
		(stroke
			(width 0)
			(type default)
		)
	)
	(bus_entry
		(at 278.13 71.12)
		(size -2.54 2.54)
		(stroke
			(width 0)
			(type default)
		)
	)
	(bus_entry
		(at 173.99 96.52)
		(size -2.54 2.54)
		(stroke
			(width 0)
			(type default)
		)
	)
	(bus_entry
		(at 278.13 78.74)
		(size -2.54 2.54)
		(stroke
			(width 0)
			(type default)
		)
	)
	(bus_entry
		(at 173.99 66.04)
		(size -2.54 2.54)
		(stroke
			(width 0)
			(type default)
		)
	)
	(bus_entry
		(at 278.13 76.2)
		(size -2.54 2.54)
		(stroke
			(width 0)
			(type default)
		)
	)
	(bus_entry
		(at 99.06 73.66)
		(size 2.54 2.54)
		(stroke
			(width 0)
			(type default)
		)
	)
	(bus_entry
		(at 278.13 63.5)
		(size -2.54 2.54)
		(stroke
			(width 0)
			(type default)
		)
	)
	(bus_entry
		(at 204.47 68.58)
		(size 2.54 2.54)
		(stroke
			(width 0)
			(type default)
		)
	)
	(bus_entry
		(at 204.47 88.9)
		(size 2.54 2.54)
		(stroke
			(width 0)
			(type default)
		)
	)
	(bus_entry
		(at 173.99 83.82)
		(size -2.54 2.54)
		(stroke
			(width 0)
			(type default)
		)
	)
	(bus_entry
		(at 278.13 73.66)
		(size -2.54 2.54)
		(stroke
			(width 0)
			(type default)
		)
	)
	(bus_entry
		(at 278.13 101.6)
		(size -2.54 2.54)
		(stroke
			(width 0)
			(type default)
		)
	)
	(bus_entry
		(at 173.99 106.68)
		(size -2.54 2.54)
		(stroke
			(width 0)
			(type default)
		)
	)
	(bus_entry
		(at 278.13 114.3)
		(size -2.54 2.54)
		(stroke
			(width 0)
			(type default)
		)
	)
	(bus_entry
		(at 173.99 68.58)
		(size -2.54 2.54)
		(stroke
			(width 0)
			(type default)
		)
	)
	(bus_entry
		(at 99.06 68.58)
		(size 2.54 2.54)
		(stroke
			(width 0)
			(type default)
		)
	)
	(bus_entry
		(at 173.99 104.14)
		(size -2.54 2.54)
		(stroke
			(width 0)
			(type default)
		)
	)
	(bus_entry
		(at 204.47 76.2)
		(size 2.54 2.54)
		(stroke
			(width 0)
			(type default)
		)
	)
	(bus_entry
		(at 173.99 111.76)
		(size -2.54 2.54)
		(stroke
			(width 0)
			(type default)
		)
	)
	(bus_entry
		(at 278.13 109.22)
		(size -2.54 2.54)
		(stroke
			(width 0)
			(type default)
		)
	)
	(bus_entry
		(at 173.99 114.3)
		(size -2.54 2.54)
		(stroke
			(width 0)
			(type default)
		)
	)
	(bus_entry
		(at 204.47 91.44)
		(size 2.54 2.54)
		(stroke
			(width 0)
			(type default)
		)
	)
	(bus_entry
		(at 173.99 88.9)
		(size -2.54 2.54)
		(stroke
			(width 0)
			(type default)
		)
	)
	(bus_entry
		(at 278.13 68.58)
		(size -2.54 2.54)
		(stroke
			(width 0)
			(type default)
		)
	)
	(bus_entry
		(at 173.99 91.44)
		(size -2.54 2.54)
		(stroke
			(width 0)
			(type default)
		)
	)
	(bus_entry
		(at 278.13 81.28)
		(size -2.54 2.54)
		(stroke
			(width 0)
			(type default)
		)
	)
	(bus_entry
		(at 99.06 71.12)
		(size 2.54 2.54)
		(stroke
			(width 0)
			(type default)
		)
	)
	(bus_entry
		(at 278.13 106.68)
		(size -2.54 2.54)
		(stroke
			(width 0)
			(type default)
		)
	)
	(bus_entry
		(at 173.99 93.98)
		(size -2.54 2.54)
		(stroke
			(width 0)
			(type default)
		)
	)
	(bus_entry
		(at 204.47 86.36)
		(size 2.54 2.54)
		(stroke
			(width 0)
			(type default)
		)
	)
	(bus_entry
		(at 278.13 104.14)
		(size -2.54 2.54)
		(stroke
			(width 0)
			(type default)
		)
	)
	(bus_entry
		(at 278.13 83.82)
		(size -2.54 2.54)
		(stroke
			(width 0)
			(type default)
		)
	)
	(bus_entry
		(at 204.47 83.82)
		(size 2.54 2.54)
		(stroke
			(width 0)
			(type default)
		)
	)
	(bus_entry
		(at 173.99 99.06)
		(size -2.54 2.54)
		(stroke
			(width 0)
			(type default)
		)
	)
	(bus_entry
		(at 204.47 78.74)
		(size 2.54 2.54)
		(stroke
			(width 0)
			(type default)
		)
	)
	(bus_entry
		(at 278.13 96.52)
		(size -2.54 2.54)
		(stroke
			(width 0)
			(type default)
		)
	)
	(bus_entry
		(at 99.06 86.36)
		(size 2.54 2.54)
		(stroke
			(width 0)
			(type default)
		)
	)
	(bus_entry
		(at 278.13 99.06)
		(size -2.54 2.54)
		(stroke
			(width 0)
			(type default)
		)
	)
	(bus_entry
		(at 173.99 73.66)
		(size -2.54 2.54)
		(stroke
			(width 0)
			(type default)
		)
	)
	(bus_entry
		(at 278.13 86.36)
		(size -2.54 2.54)
		(stroke
			(width 0)
			(type default)
		)
	)
	(bus_entry
		(at 173.99 76.2)
		(size -2.54 2.54)
		(stroke
			(width 0)
			(type default)
		)
	)
	(bus_entry
		(at 99.06 83.82)
		(size 2.54 2.54)
		(stroke
			(width 0)
			(type default)
		)
	)
	(bus_entry
		(at 204.47 71.12)
		(size 2.54 2.54)
		(stroke
			(width 0)
			(type default)
		)
	)
	(bus_entry
		(at 278.13 91.44)
		(size -2.54 2.54)
		(stroke
			(width 0)
			(type default)
		)
	)
	(bus_entry
		(at 99.06 91.44)
		(size 2.54 2.54)
		(stroke
			(width 0)
			(type default)
		)
	)
	(bus_entry
		(at 99.06 78.74)
		(size 2.54 2.54)
		(stroke
			(width 0)
			(type default)
		)
	)
	(bus_entry
		(at 173.99 60.96)
		(size -2.54 2.54)
		(stroke
			(width 0)
			(type default)
		)
	)
	(bus_entry
		(at 99.06 76.2)
		(size 2.54 2.54)
		(stroke
			(width 0)
			(type default)
		)
	)
	(bus_entry
		(at 278.13 66.04)
		(size -2.54 2.54)
		(stroke
			(width 0)
			(type default)
		)
	)
	(bus_entry
		(at 278.13 111.76)
		(size -2.54 2.54)
		(stroke
			(width 0)
			(type default)
		)
	)
	(bus_entry
		(at 278.13 93.98)
		(size -2.54 2.54)
		(stroke
			(width 0)
			(type default)
		)
	)
	(bus_entry
		(at 173.99 81.28)
		(size -2.54 2.54)
		(stroke
			(width 0)
			(type default)
		)
	)
	(bus_entry
		(at 99.06 96.52)
		(size 2.54 2.54)
		(stroke
			(width 0)
			(type default)
		)
	)
	(bus_entry
		(at 173.99 78.74)
		(size -2.54 2.54)
		(stroke
			(width 0)
			(type default)
		)
	)
	(bus_entry
		(at 204.47 81.28)
		(size 2.54 2.54)
		(stroke
			(width 0)
			(type default)
		)
	)
	(wire
		(pts
			(xy 259.08 86.36) (xy 275.59 86.36)
		)
		(stroke
			(width 0)
			(type default)
		)
	)
	(wire
		(pts
			(xy 189.23 228.6) (xy 196.85 228.6)
		)
		(stroke
			(width 0)
			(type default)
		)
	)
	(bus
		(pts
			(xy 99.06 64.77) (xy 99.06 68.58)
		)
		(stroke
			(width 0)
			(type default)
		)
	)
	(wire
		(pts
			(xy 147.32 209.55) (xy 147.32 210.82)
		)
		(stroke
			(width 0)
			(type default)
		)
	)
	(wire
		(pts
			(xy 101.6 91.44) (xy 120.65 91.44)
		)
		(stroke
			(width 0)
			(type default)
		)
	)
	(wire
		(pts
			(xy 187.96 186.69) (xy 187.96 187.96)
		)
		(stroke
			(width 0)
			(type default)
		)
	)
	(wire
		(pts
			(xy 147.32 194.31) (xy 147.32 195.58)
		)
		(stroke
			(width 0)
			(type default)
		)
	)
	(bus
		(pts
			(xy 278.13 81.28) (xy 278.13 83.82)
		)
		(stroke
			(width 0)
			(type default)
		)
	)
	(wire
		(pts
			(xy 204.47 187.96) (xy 212.09 187.96)
		)
		(stroke
			(width 0)
			(type default)
		)
	)
	(polyline
		(pts
			(xy 281.94 175.26) (xy 281.94 179.07)
		)
		(stroke
			(width 0)
			(type default)
		)
	)
	(wire
		(pts
			(xy 259.08 81.28) (xy 275.59 81.28)
		)
		(stroke
			(width 0)
			(type default)
		)
	)
	(wire
		(pts
			(xy 262.89 187.96) (xy 262.89 189.23)
		)
		(stroke
			(width 0)
			(type default)
		)
	)
	(wire
		(pts
			(xy 147.32 236.22) (xy 154.94 236.22)
		)
		(stroke
			(width 0)
			(type default)
		)
	)
	(wire
		(pts
			(xy 147.32 186.69) (xy 147.32 187.96)
		)
		(stroke
			(width 0)
			(type default)
		)
	)
	(wire
		(pts
			(xy 269.24 210.82) (xy 269.24 209.55)
		)
		(stroke
			(width 0)
			(type default)
		)
	)
	(bus
		(pts
			(xy 278.13 73.66) (xy 278.13 76.2)
		)
		(stroke
			(width 0)
			(type default)
		)
	)
	(bus
		(pts
			(xy 99.06 73.66) (xy 99.06 76.2)
		)
		(stroke
			(width 0)
			(type default)
		)
	)
	(wire
		(pts
			(xy 120.65 124.46) (xy 118.11 124.46)
		)
		(stroke
			(width 0)
			(type default)
		)
	)
	(wire
		(pts
			(xy 259.08 109.22) (xy 275.59 109.22)
		)
		(stroke
			(width 0)
			(type default)
		)
	)
	(wire
		(pts
			(xy 154.94 101.6) (xy 171.45 101.6)
		)
		(stroke
			(width 0)
			(type default)
		)
	)
	(wire
		(pts
			(xy 101.6 81.28) (xy 120.65 81.28)
		)
		(stroke
			(width 0)
			(type default)
		)
	)
	(wire
		(pts
			(xy 238.76 208.28) (xy 238.76 209.55)
		)
		(stroke
			(width 0)
			(type default)
		)
	)
	(wire
		(pts
			(xy 204.47 236.22) (xy 212.09 236.22)
		)
		(stroke
			(width 0)
			(type default)
		)
	)
	(bus
		(pts
			(xy 204.47 73.66) (xy 204.47 76.2)
		)
		(stroke
			(width 0)
			(type default)
		)
	)
	(wire
		(pts
			(xy 120.65 68.58) (xy 115.57 68.58)
		)
		(stroke
			(width 0)
			(type default)
		)
	)
	(wire
		(pts
			(xy 261.62 209.55) (xy 261.62 210.82)
		)
		(stroke
			(width 0)
			(type default)
		)
	)
	(wire
		(pts
			(xy 247.65 187.96) (xy 247.65 189.23)
		)
		(stroke
			(width 0)
			(type default)
		)
	)
	(wire
		(pts
			(xy 154.94 73.66) (xy 171.45 73.66)
		)
		(stroke
			(width 0)
			(type default)
		)
	)
	(wire
		(pts
			(xy 147.32 195.58) (xy 154.94 195.58)
		)
		(stroke
			(width 0)
			(type default)
		)
	)
	(wire
		(pts
			(xy 154.94 236.22) (xy 154.94 237.49)
		)
		(stroke
			(width 0)
			(type default)
		)
	)
	(wire
		(pts
			(xy 247.65 194.31) (xy 247.65 195.58)
		)
		(stroke
			(width 0)
			(type default)
		)
	)
	(wire
		(pts
			(xy 259.08 104.14) (xy 275.59 104.14)
		)
		(stroke
			(width 0)
			(type default)
		)
	)
	(bus
		(pts
			(xy 99.06 86.36) (xy 99.06 88.9)
		)
		(stroke
			(width 0)
			(type default)
		)
	)
	(wire
		(pts
			(xy 196.85 209.55) (xy 204.47 209.55)
		)
		(stroke
			(width 0)
			(type default)
		)
	)
	(wire
		(pts
			(xy 207.01 71.12) (xy 224.79 71.12)
		)
		(stroke
			(width 0)
			(type default)
		)
	)
	(wire
		(pts
			(xy 147.32 227.33) (xy 147.32 228.6)
		)
		(stroke
			(width 0)
			(type default)
		)
	)
	(wire
		(pts
			(xy 196.85 236.22) (xy 204.47 236.22)
		)
		(stroke
			(width 0)
			(type default)
		)
	)
	(wire
		(pts
			(xy 176.53 194.31) (xy 176.53 195.58)
		)
		(stroke
			(width 0)
			(type default)
		)
	)
	(wire
		(pts
			(xy 204.47 234.95) (xy 204.47 236.22)
		)
		(stroke
			(width 0)
			(type default)
		)
	)
	(bus
		(pts
			(xy 99.06 81.28) (xy 99.06 83.82)
		)
		(stroke
			(width 0)
			(type default)
		)
	)
	(wire
		(pts
			(xy 196.85 194.31) (xy 196.85 195.58)
		)
		(stroke
			(width 0)
			(type default)
		)
	)
	(bus
		(pts
			(xy 278.13 66.04) (xy 278.13 68.58)
		)
		(stroke
			(width 0)
			(type default)
		)
	)
	(bus
		(pts
			(xy 173.99 106.68) (xy 173.99 109.22)
		)
		(stroke
			(width 0)
			(type default)
		)
	)
	(wire
		(pts
			(xy 238.76 209.55) (xy 238.76 210.82)
		)
		(stroke
			(width 0)
			(type default)
		)
	)
	(wire
		(pts
			(xy 270.51 195.58) (xy 270.51 196.85)
		)
		(stroke
			(width 0)
			(type default)
		)
	)
	(wire
		(pts
			(xy 262.89 195.58) (xy 270.51 195.58)
		)
		(stroke
			(width 0)
			(type default)
		)
	)
	(wire
		(pts
			(xy 154.94 209.55) (xy 154.94 210.82)
		)
		(stroke
			(width 0)
			(type default)
		)
	)
	(bus
		(pts
			(xy 203.2 66.04) (xy 204.47 67.31)
		)
		(stroke
			(width 0)
			(type default)
		)
	)
	(wire
		(pts
			(xy 154.94 88.9) (xy 171.45 88.9)
		)
		(stroke
			(width 0)
			(type default)
		)
	)
	(wire
		(pts
			(xy 154.94 109.22) (xy 171.45 109.22)
		)
		(stroke
			(width 0)
			(type default)
		)
	)
	(wire
		(pts
			(xy 204.47 195.58) (xy 212.09 195.58)
		)
		(stroke
			(width 0)
			(type default)
		)
	)
	(bus
		(pts
			(xy 204.47 86.36) (xy 204.47 88.9)
		)
		(stroke
			(width 0)
			(type default)
		)
	)
	(wire
		(pts
			(xy 259.08 73.66) (xy 275.59 73.66)
		)
		(stroke
			(width 0)
			(type default)
		)
	)
	(wire
		(pts
			(xy 187.96 195.58) (xy 196.85 195.58)
		)
		(stroke
			(width 0)
			(type default)
		)
	)
	(wire
		(pts
			(xy 246.38 209.55) (xy 254 209.55)
		)
		(stroke
			(width 0)
			(type default)
		)
	)
	(wire
		(pts
			(xy 114.3 106.68) (xy 114.3 107.95)
		)
		(stroke
			(width 0)
			(type default)
		)
	)
	(bus
		(pts
			(xy 278.13 68.58) (xy 278.13 71.12)
		)
		(stroke
			(width 0)
			(type default)
		)
	)
	(bus
		(pts
			(xy 201.93 66.04) (xy 203.2 66.04)
		)
		(stroke
			(width 0)
			(type default)
		)
	)
	(wire
		(pts
			(xy 154.94 93.98) (xy 171.45 93.98)
		)
		(stroke
			(width 0)
			(type default)
		)
	)
	(wire
		(pts
			(xy 114.3 99.06) (xy 120.65 99.06)
		)
		(stroke
			(width 0)
			(type default)
		)
	)
	(bus
		(pts
			(xy 278.13 93.98) (xy 278.13 96.52)
		)
		(stroke
			(width 0)
			(type default)
		)
	)
	(wire
		(pts
			(xy 115.57 63.5) (xy 120.65 63.5)
		)
		(stroke
			(width 0)
			(type default)
		)
	)
	(wire
		(pts
			(xy 189.23 229.87) (xy 189.23 228.6)
		)
		(stroke
			(width 0)
			(type default)
		)
	)
	(wire
		(pts
			(xy 269.24 217.17) (xy 269.24 218.44)
		)
		(stroke
			(width 0)
			(type default)
		)
	)
	(wire
		(pts
			(xy 154.94 228.6) (xy 154.94 229.87)
		)
		(stroke
			(width 0)
			(type default)
		)
	)
	(bus
		(pts
			(xy 173.99 83.82) (xy 173.99 86.36)
		)
		(stroke
			(width 0)
			(type default)
		)
	)
	(wire
		(pts
			(xy 101.6 71.12) (xy 120.65 71.12)
		)
		(stroke
			(width 0)
			(type default)
		)
	)
	(wire
		(pts
			(xy 207.01 91.44) (xy 224.79 91.44)
		)
		(stroke
			(width 0)
			(type default)
		)
	)
	(bus
		(pts
			(xy 278.13 71.12) (xy 278.13 73.66)
		)
		(stroke
			(width 0)
			(type default)
		)
	)
	(wire
		(pts
			(xy 154.94 195.58) (xy 154.94 196.85)
		)
		(stroke
			(width 0)
			(type default)
		)
	)
	(bus
		(pts
			(xy 278.13 83.82) (xy 278.13 86.36)
		)
		(stroke
			(width 0)
			(type default)
		)
	)
	(wire
		(pts
			(xy 259.08 71.12) (xy 275.59 71.12)
		)
		(stroke
			(width 0)
			(type default)
		)
	)
	(bus
		(pts
			(xy 204.47 71.12) (xy 204.47 73.66)
		)
		(stroke
			(width 0)
			(type default)
		)
	)
	(wire
		(pts
			(xy 154.94 91.44) (xy 171.45 91.44)
		)
		(stroke
			(width 0)
			(type default)
		)
	)
	(bus
		(pts
			(xy 173.99 59.69) (xy 173.99 60.96)
		)
		(stroke
			(width 0)
			(type default)
		)
	)
	(wire
		(pts
			(xy 147.32 229.87) (xy 147.32 228.6)
		)
		(stroke
			(width 0)
			(type default)
		)
	)
	(wire
		(pts
			(xy 270.51 194.31) (xy 270.51 195.58)
		)
		(stroke
			(width 0)
			(type default)
		)
	)
	(wire
		(pts
			(xy 246.38 217.17) (xy 254 217.17)
		)
		(stroke
			(width 0)
			(type default)
		)
	)
	(wire
		(pts
			(xy 154.94 63.5) (xy 171.45 63.5)
		)
		(stroke
			(width 0)
			(type default)
		)
	)
	(bus
		(pts
			(xy 204.47 78.74) (xy 204.47 81.28)
		)
		(stroke
			(width 0)
			(type default)
		)
	)
	(wire
		(pts
			(xy 196.85 209.55) (xy 196.85 210.82)
		)
		(stroke
			(width 0)
			(type default)
		)
	)
	(wire
		(pts
			(xy 254 209.55) (xy 261.62 209.55)
		)
		(stroke
			(width 0)
			(type default)
		)
	)
	(wire
		(pts
			(xy 189.23 209.55) (xy 196.85 209.55)
		)
		(stroke
			(width 0)
			(type default)
		)
	)
	(wire
		(pts
			(xy 196.85 187.96) (xy 196.85 189.23)
		)
		(stroke
			(width 0)
			(type default)
		)
	)
	(wire
		(pts
			(xy 154.94 71.12) (xy 171.45 71.12)
		)
		(stroke
			(width 0)
			(type default)
		)
	)
	(wire
		(pts
			(xy 259.08 68.58) (xy 275.59 68.58)
		)
		(stroke
			(width 0)
			(type default)
		)
	)
	(wire
		(pts
			(xy 212.09 215.9) (xy 212.09 217.17)
		)
		(stroke
			(width 0)
			(type default)
		)
	)
	(wire
		(pts
			(xy 204.47 217.17) (xy 212.09 217.17)
		)
		(stroke
			(width 0)
			(type default)
		)
	)
	(bus
		(pts
			(xy 99.06 68.58) (xy 99.06 71.12)
		)
		(stroke
			(width 0)
			(type default)
		)
	)
	(wire
		(pts
			(xy 247.65 186.69) (xy 247.65 187.96)
		)
		(stroke
			(width 0)
			(type default)
		)
	)
	(wire
		(pts
			(xy 101.6 88.9) (xy 120.65 88.9)
		)
		(stroke
			(width 0)
			(type default)
		)
	)
	(wire
		(pts
			(xy 147.32 209.55) (xy 154.94 209.55)
		)
		(stroke
			(width 0)
			(type default)
		)
	)
	(bus
		(pts
			(xy 278.13 104.14) (xy 278.13 106.68)
		)
		(stroke
			(width 0)
			(type default)
		)
	)
	(bus
		(pts
			(xy 173.99 63.5) (xy 173.99 66.04)
		)
		(stroke
			(width 0)
			(type default)
		)
	)
	(wire
		(pts
			(xy 154.94 194.31) (xy 154.94 195.58)
		)
		(stroke
			(width 0)
			(type default)
		)
	)
	(wire
		(pts
			(xy 101.6 76.2) (xy 120.65 76.2)
		)
		(stroke
			(width 0)
			(type default)
		)
	)
	(polyline
		(pts
			(xy 166.37 175.26) (xy 166.37 250.19)
		)
		(stroke
			(width 0)
			(type default)
		)
	)
	(wire
		(pts
			(xy 130.81 208.28) (xy 130.81 210.82)
		)
		(stroke
			(width 0)
			(type default)
		)
	)
	(wire
		(pts
			(xy 187.96 187.96) (xy 187.96 189.23)
		)
		(stroke
			(width 0)
			(type default)
		)
	)
	(wire
		(pts
			(xy 212.09 195.58) (xy 212.09 196.85)
		)
		(stroke
			(width 0)
			(type default)
		)
	)
	(wire
		(pts
			(xy 269.24 215.9) (xy 269.24 217.17)
		)
		(stroke
			(width 0)
			(type default)
		)
	)
	(wire
		(pts
			(xy 259.08 101.6) (xy 275.59 101.6)
		)
		(stroke
			(width 0)
			(type default)
		)
	)
	(wire
		(pts
			(xy 189.23 227.33) (xy 189.23 228.6)
		)
		(stroke
			(width 0)
			(type default)
		)
	)
	(wire
		(pts
			(xy 262.89 187.96) (xy 270.51 187.96)
		)
		(stroke
			(width 0)
			(type default)
		)
	)
	(wire
		(pts
			(xy 207.01 76.2) (xy 224.79 76.2)
		)
		(stroke
			(width 0)
			(type default)
		)
	)
	(wire
		(pts
			(xy 247.65 187.96) (xy 255.27 187.96)
		)
		(stroke
			(width 0)
			(type default)
		)
	)
	(bus
		(pts
			(xy 278.13 78.74) (xy 278.13 81.28)
		)
		(stroke
			(width 0)
			(type default)
		)
	)
	(wire
		(pts
			(xy 154.94 111.76) (xy 171.45 111.76)
		)
		(stroke
			(width 0)
			(type default)
		)
	)
	(wire
		(pts
			(xy 130.81 185.42) (xy 130.81 187.96)
		)
		(stroke
			(width 0)
			(type default)
		)
	)
	(wire
		(pts
			(xy 154.94 66.04) (xy 171.45 66.04)
		)
		(stroke
			(width 0)
			(type default)
		)
	)
	(bus
		(pts
			(xy 99.06 71.12) (xy 99.06 73.66)
		)
		(stroke
			(width 0)
			(type default)
		)
	)
	(polyline
		(pts
			(xy 119.38 175.26) (xy 281.94 175.26)
		)
		(stroke
			(width 0)
			(type default)
		)
	)
	(wire
		(pts
			(xy 219.71 68.58) (xy 219.71 63.5)
		)
		(stroke
			(width 0)
			(type default)
		)
	)
	(wire
		(pts
			(xy 154.94 114.3) (xy 171.45 114.3)
		)
		(stroke
			(width 0)
			(type default)
		)
	)
	(wire
		(pts
			(xy 261.62 215.9) (xy 261.62 217.17)
		)
		(stroke
			(width 0)
			(type default)
		)
	)
	(wire
		(pts
			(xy 237.49 186.69) (xy 237.49 189.23)
		)
		(stroke
			(width 0)
			(type default)
		)
	)
	(wire
		(pts
			(xy 259.08 111.76) (xy 275.59 111.76)
		)
		(stroke
			(width 0)
			(type default)
		)
	)
	(wire
		(pts
			(xy 262.89 194.31) (xy 262.89 195.58)
		)
		(stroke
			(width 0)
			(type default)
		)
	)
	(bus
		(pts
			(xy 278.13 109.22) (xy 278.13 111.76)
		)
		(stroke
			(width 0)
			(type default)
		)
	)
	(wire
		(pts
			(xy 259.08 66.04) (xy 275.59 66.04)
		)
		(stroke
			(width 0)
			(type default)
		)
	)
	(wire
		(pts
			(xy 204.47 187.96) (xy 204.47 189.23)
		)
		(stroke
			(width 0)
			(type default)
		)
	)
	(bus
		(pts
			(xy 173.99 78.74) (xy 173.99 81.28)
		)
		(stroke
			(width 0)
			(type default)
		)
	)
	(wire
		(pts
			(xy 187.96 194.31) (xy 187.96 195.58)
		)
		(stroke
			(width 0)
			(type default)
		)
	)
	(wire
		(pts
			(xy 238.76 217.17) (xy 246.38 217.17)
		)
		(stroke
			(width 0)
			(type default)
		)
	)
	(wire
		(pts
			(xy 212.09 218.44) (xy 212.09 217.17)
		)
		(stroke
			(width 0)
			(type default)
		)
	)
	(wire
		(pts
			(xy 255.27 194.31) (xy 255.27 195.58)
		)
		(stroke
			(width 0)
			(type default)
		)
	)
	(bus
		(pts
			(xy 278.13 63.5) (xy 278.13 66.04)
		)
		(stroke
			(width 0)
			(type default)
		)
	)
	(bus
		(pts
			(xy 278.13 60.96) (xy 278.13 63.5)
		)
		(stroke
			(width 0)
			(type default)
		)
	)
	(wire
		(pts
			(xy 212.09 236.22) (xy 212.09 237.49)
		)
		(stroke
			(width 0)
			(type default)
		)
	)
	(wire
		(pts
			(xy 254 209.55) (xy 254 210.82)
		)
		(stroke
			(width 0)
			(type default)
		)
	)
	(wire
		(pts
			(xy 196.85 215.9) (xy 196.85 217.17)
		)
		(stroke
			(width 0)
			(type default)
		)
	)
	(bus
		(pts
			(xy 278.13 96.52) (xy 278.13 99.06)
		)
		(stroke
			(width 0)
			(type default)
		)
	)
	(wire
		(pts
			(xy 259.08 93.98) (xy 275.59 93.98)
		)
		(stroke
			(width 0)
			(type default)
		)
	)
	(wire
		(pts
			(xy 207.01 93.98) (xy 224.79 93.98)
		)
		(stroke
			(width 0)
			(type default)
		)
	)
	(wire
		(pts
			(xy 237.49 194.31) (xy 237.49 195.58)
		)
		(stroke
			(width 0)
			(type default)
		)
	)
	(wire
		(pts
			(xy 154.94 83.82) (xy 171.45 83.82)
		)
		(stroke
			(width 0)
			(type default)
		)
	)
	(wire
		(pts
			(xy 196.85 187.96) (xy 204.47 187.96)
		)
		(stroke
			(width 0)
			(type default)
		)
	)
	(wire
		(pts
			(xy 212.09 234.95) (xy 212.09 236.22)
		)
		(stroke
			(width 0)
			(type default)
		)
	)
	(bus
		(pts
			(xy 173.99 88.9) (xy 173.99 91.44)
		)
		(stroke
			(width 0)
			(type default)
		)
	)
	(polyline
		(pts
			(xy 119.38 250.19) (xy 281.94 250.19)
		)
		(stroke
			(width 0)
			(type default)
		)
	)
	(wire
		(pts
			(xy 115.57 54.61) (xy 115.57 63.5)
		)
		(stroke
			(width 0)
			(type default)
		)
	)
	(wire
		(pts
			(xy 220.98 121.92) (xy 224.79 121.92)
		)
		(stroke
			(width 0)
			(type default)
		)
	)
	(wire
		(pts
			(xy 176.53 208.28) (xy 176.53 210.82)
		)
		(stroke
			(width 0)
			(type default)
		)
	)
	(wire
		(pts
			(xy 224.79 68.58) (xy 219.71 68.58)
		)
		(stroke
			(width 0)
			(type default)
		)
	)
	(bus
		(pts
			(xy 173.99 93.98) (xy 173.99 96.52)
		)
		(stroke
			(width 0)
			(type default)
		)
	)
	(wire
		(pts
			(xy 259.08 91.44) (xy 275.59 91.44)
		)
		(stroke
			(width 0)
			(type default)
		)
	)
	(bus
		(pts
			(xy 173.99 68.58) (xy 173.99 71.12)
		)
		(stroke
			(width 0)
			(type default)
		)
	)
	(bus
		(pts
			(xy 173.99 91.44) (xy 173.99 93.98)
		)
		(stroke
			(width 0)
			(type default)
		)
	)
	(wire
		(pts
			(xy 238.76 209.55) (xy 246.38 209.55)
		)
		(stroke
			(width 0)
			(type default)
		)
	)
	(wire
		(pts
			(xy 120.65 66.04) (xy 106.68 66.04)
		)
		(stroke
			(width 0)
			(type default)
		)
	)
	(wire
		(pts
			(xy 147.32 208.28) (xy 147.32 209.55)
		)
		(stroke
			(width 0)
			(type default)
		)
	)
	(bus
		(pts
			(xy 204.47 68.58) (xy 204.47 71.12)
		)
		(stroke
			(width 0)
			(type default)
		)
	)
	(wire
		(pts
			(xy 147.32 234.95) (xy 147.32 236.22)
		)
		(stroke
			(width 0)
			(type default)
		)
	)
	(bus
		(pts
			(xy 173.99 111.76) (xy 173.99 114.3)
		)
		(stroke
			(width 0)
			(type default)
		)
	)
	(wire
		(pts
			(xy 115.57 68.58) (xy 115.57 63.5)
		)
		(stroke
			(width 0)
			(type default)
		)
	)
	(wire
		(pts
			(xy 187.96 187.96) (xy 196.85 187.96)
		)
		(stroke
			(width 0)
			(type default)
		)
	)
	(wire
		(pts
			(xy 219.71 54.61) (xy 219.71 63.5)
		)
		(stroke
			(width 0)
			(type default)
		)
	)
	(wire
		(pts
			(xy 207.01 78.74) (xy 224.79 78.74)
		)
		(stroke
			(width 0)
			(type default)
		)
	)
	(wire
		(pts
			(xy 259.08 96.52) (xy 275.59 96.52)
		)
		(stroke
			(width 0)
			(type default)
		)
	)
	(wire
		(pts
			(xy 154.94 217.17) (xy 154.94 218.44)
		)
		(stroke
			(width 0)
			(type default)
		)
	)
	(wire
		(pts
			(xy 207.01 81.28) (xy 224.79 81.28)
		)
		(stroke
			(width 0)
			(type default)
		)
	)
	(polyline
		(pts
			(xy 119.38 179.07) (xy 119.38 250.19)
		)
		(stroke
			(width 0)
			(type default)
		)
	)
	(wire
		(pts
			(xy 247.65 195.58) (xy 255.27 195.58)
		)
		(stroke
			(width 0)
			(type default)
		)
	)
	(wire
		(pts
			(xy 204.47 194.31) (xy 204.47 195.58)
		)
		(stroke
			(width 0)
			(type default)
		)
	)
	(wire
		(pts
			(xy 204.47 209.55) (xy 212.09 209.55)
		)
		(stroke
			(width 0)
			(type default)
		)
	)
	(bus
		(pts
			(xy 99.06 78.74) (xy 99.06 81.28)
		)
		(stroke
			(width 0)
			(type default)
		)
	)
	(wire
		(pts
			(xy 114.3 99.06) (xy 114.3 101.6)
		)
		(stroke
			(width 0)
			(type default)
		)
	)
	(wire
		(pts
			(xy 255.27 195.58) (xy 262.89 195.58)
		)
		(stroke
			(width 0)
			(type default)
		)
	)
	(wire
		(pts
			(xy 189.23 217.17) (xy 196.85 217.17)
		)
		(stroke
			(width 0)
			(type default)
		)
	)
	(wire
		(pts
			(xy 246.38 209.55) (xy 246.38 210.82)
		)
		(stroke
			(width 0)
			(type default)
		)
	)
	(bus
		(pts
			(xy 173.99 81.28) (xy 173.99 83.82)
		)
		(stroke
			(width 0)
			(type default)
		)
	)
	(bus
		(pts
			(xy 96.52 63.5) (xy 97.79 63.5)
		)
		(stroke
			(width 0)
			(type default)
		)
	)
	(wire
		(pts
			(xy 154.94 68.58) (xy 171.45 68.58)
		)
		(stroke
			(width 0)
			(type default)
		)
	)
	(wire
		(pts
			(xy 207.01 88.9) (xy 224.79 88.9)
		)
		(stroke
			(width 0)
			(type default)
		)
	)
	(wire
		(pts
			(xy 118.11 124.46) (xy 118.11 128.27)
		)
		(stroke
			(width 0)
			(type default)
		)
	)
	(wire
		(pts
			(xy 259.08 63.5) (xy 275.59 63.5)
		)
		(stroke
			(width 0)
			(type default)
		)
	)
	(bus
		(pts
			(xy 278.13 88.9) (xy 278.13 91.44)
		)
		(stroke
			(width 0)
			(type default)
		)
	)
	(wire
		(pts
			(xy 196.85 229.87) (xy 196.85 228.6)
		)
		(stroke
			(width 0)
			(type default)
		)
	)
	(wire
		(pts
			(xy 189.23 208.28) (xy 189.23 209.55)
		)
		(stroke
			(width 0)
			(type default)
		)
	)
	(wire
		(pts
			(xy 259.08 116.84) (xy 275.59 116.84)
		)
		(stroke
			(width 0)
			(type default)
		)
	)
	(bus
		(pts
			(xy 176.53 58.42) (xy 175.26 58.42)
		)
		(stroke
			(width 0)
			(type default)
		)
	)
	(wire
		(pts
			(xy 101.6 86.36) (xy 120.65 86.36)
		)
		(stroke
			(width 0)
			(type default)
		)
	)
	(wire
		(pts
			(xy 101.6 93.98) (xy 120.65 93.98)
		)
		(stroke
			(width 0)
			(type default)
		)
	)
	(bus
		(pts
			(xy 173.99 66.04) (xy 173.99 68.58)
		)
		(stroke
			(width 0)
			(type default)
		)
	)
	(wire
		(pts
			(xy 196.85 228.6) (xy 204.47 228.6)
		)
		(stroke
			(width 0)
			(type default)
		)
	)
	(wire
		(pts
			(xy 259.08 106.68) (xy 275.59 106.68)
		)
		(stroke
			(width 0)
			(type default)
		)
	)
	(wire
		(pts
			(xy 196.85 234.95) (xy 196.85 236.22)
		)
		(stroke
			(width 0)
			(type default)
		)
	)
	(bus
		(pts
			(xy 99.06 76.2) (xy 99.06 78.74)
		)
		(stroke
			(width 0)
			(type default)
		)
	)
	(wire
		(pts
			(xy 212.09 187.96) (xy 212.09 189.23)
		)
		(stroke
			(width 0)
			(type default)
		)
	)
	(wire
		(pts
			(xy 101.6 78.74) (xy 120.65 78.74)
		)
		(stroke
			(width 0)
			(type default)
		)
	)
	(wire
		(pts
			(xy 154.94 124.46) (xy 157.48 124.46)
		)
		(stroke
			(width 0)
			(type default)
		)
	)
	(wire
		(pts
			(xy 207.01 83.82) (xy 224.79 83.82)
		)
		(stroke
			(width 0)
			(type default)
		)
	)
	(wire
		(pts
			(xy 261.62 209.55) (xy 269.24 209.55)
		)
		(stroke
			(width 0)
			(type default)
		)
	)
	(bus
		(pts
			(xy 278.13 86.36) (xy 278.13 88.9)
		)
		(stroke
			(width 0)
			(type default)
		)
	)
	(wire
		(pts
			(xy 207.01 86.36) (xy 224.79 86.36)
		)
		(stroke
			(width 0)
			(type default)
		)
	)
	(wire
		(pts
			(xy 154.94 234.95) (xy 154.94 236.22)
		)
		(stroke
			(width 0)
			(type default)
		)
	)
	(bus
		(pts
			(xy 173.99 96.52) (xy 173.99 99.06)
		)
		(stroke
			(width 0)
			(type default)
		)
	)
	(polyline
		(pts
			(xy 224.79 175.26) (xy 224.79 250.19)
		)
		(stroke
			(width 0)
			(type default)
		)
	)
	(bus
		(pts
			(xy 173.99 104.14) (xy 173.99 106.68)
		)
		(stroke
			(width 0)
			(type default)
		)
	)
	(wire
		(pts
			(xy 101.6 73.66) (xy 120.65 73.66)
		)
		(stroke
			(width 0)
			(type default)
		)
	)
	(wire
		(pts
			(xy 238.76 215.9) (xy 238.76 217.17)
		)
		(stroke
			(width 0)
			(type default)
		)
	)
	(wire
		(pts
			(xy 259.08 99.06) (xy 275.59 99.06)
		)
		(stroke
			(width 0)
			(type default)
		)
	)
	(wire
		(pts
			(xy 255.27 187.96) (xy 255.27 189.23)
		)
		(stroke
			(width 0)
			(type default)
		)
	)
	(wire
		(pts
			(xy 154.94 215.9) (xy 154.94 217.17)
		)
		(stroke
			(width 0)
			(type default)
		)
	)
	(wire
		(pts
			(xy 154.94 104.14) (xy 171.45 104.14)
		)
		(stroke
			(width 0)
			(type default)
		)
	)
	(bus
		(pts
			(xy 173.99 101.6) (xy 173.99 104.14)
		)
		(stroke
			(width 0)
			(type default)
		)
	)
	(bus
		(pts
			(xy 173.99 109.22) (xy 173.99 111.76)
		)
		(stroke
			(width 0)
			(type default)
		)
	)
	(wire
		(pts
			(xy 147.32 187.96) (xy 154.94 187.96)
		)
		(stroke
			(width 0)
			(type default)
		)
	)
	(wire
		(pts
			(xy 220.98 121.92) (xy 220.98 125.73)
		)
		(stroke
			(width 0)
			(type default)
		)
	)
	(wire
		(pts
			(xy 207.01 73.66) (xy 224.79 73.66)
		)
		(stroke
			(width 0)
			(type default)
		)
	)
	(wire
		(pts
			(xy 212.09 194.31) (xy 212.09 195.58)
		)
		(stroke
			(width 0)
			(type default)
		)
	)
	(wire
		(pts
			(xy 224.79 66.04) (xy 210.82 66.04)
		)
		(stroke
			(width 0)
			(type default)
		)
	)
	(wire
		(pts
			(xy 154.94 96.52) (xy 171.45 96.52)
		)
		(stroke
			(width 0)
			(type default)
		)
	)
	(wire
		(pts
			(xy 189.23 209.55) (xy 189.23 210.82)
		)
		(stroke
			(width 0)
			(type default)
		)
	)
	(wire
		(pts
			(xy 210.82 66.04) (xy 210.82 54.61)
		)
		(stroke
			(width 0)
			(type default)
		)
	)
	(wire
		(pts
			(xy 189.23 234.95) (xy 189.23 236.22)
		)
		(stroke
			(width 0)
			(type default)
		)
	)
	(bus
		(pts
			(xy 173.99 60.96) (xy 173.99 63.5)
		)
		(stroke
			(width 0)
			(type default)
		)
	)
	(wire
		(pts
			(xy 176.53 215.9) (xy 176.53 217.17)
		)
		(stroke
			(width 0)
			(type default)
		)
	)
	(wire
		(pts
			(xy 259.08 83.82) (xy 275.59 83.82)
		)
		(stroke
			(width 0)
			(type default)
		)
	)
	(wire
		(pts
			(xy 259.08 88.9) (xy 275.59 88.9)
		)
		(stroke
			(width 0)
			(type default)
		)
	)
	(bus
		(pts
			(xy 173.99 86.36) (xy 173.99 88.9)
		)
		(stroke
			(width 0)
			(type default)
		)
	)
	(wire
		(pts
			(xy 212.09 228.6) (xy 212.09 229.87)
		)
		(stroke
			(width 0)
			(type default)
		)
	)
	(bus
		(pts
			(xy 278.13 99.06) (xy 278.13 101.6)
		)
		(stroke
			(width 0)
			(type default)
		)
	)
	(wire
		(pts
			(xy 101.6 96.52) (xy 120.65 96.52)
		)
		(stroke
			(width 0)
			(type default)
		)
	)
	(bus
		(pts
			(xy 204.47 88.9) (xy 204.47 91.44)
		)
		(stroke
			(width 0)
			(type default)
		)
	)
	(wire
		(pts
			(xy 147.32 215.9) (xy 147.32 217.17)
		)
		(stroke
			(width 0)
			(type default)
		)
	)
	(bus
		(pts
			(xy 173.99 71.12) (xy 173.99 73.66)
		)
		(stroke
			(width 0)
			(type default)
		)
	)
	(wire
		(pts
			(xy 101.6 99.06) (xy 114.3 99.06)
		)
		(stroke
			(width 0)
			(type default)
		)
	)
	(bus
		(pts
			(xy 278.13 101.6) (xy 278.13 104.14)
		)
		(stroke
			(width 0)
			(type default)
		)
	)
	(wire
		(pts
			(xy 212.09 209.55) (xy 212.09 210.82)
		)
		(stroke
			(width 0)
			(type default)
		)
	)
	(wire
		(pts
			(xy 204.47 228.6) (xy 204.47 229.87)
		)
		(stroke
			(width 0)
			(type default)
		)
	)
	(polyline
		(pts
			(xy 119.38 179.07) (xy 281.94 179.07)
		)
		(stroke
			(width 0)
			(type default)
		)
	)
	(bus
		(pts
			(xy 204.47 83.82) (xy 204.47 86.36)
		)
		(stroke
			(width 0)
			(type default)
		)
	)
	(wire
		(pts
			(xy 101.6 83.82) (xy 120.65 83.82)
		)
		(stroke
			(width 0)
			(type default)
		)
	)
	(polyline
		(pts
			(xy 281.94 179.07) (xy 281.94 250.19)
		)
		(stroke
			(width 0)
			(type default)
		)
	)
	(bus
		(pts
			(xy 204.47 91.44) (xy 204.47 93.98)
		)
		(stroke
			(width 0)
			(type default)
		)
	)
	(wire
		(pts
			(xy 270.51 189.23) (xy 270.51 187.96)
		)
		(stroke
			(width 0)
			(type default)
		)
	)
	(bus
		(pts
			(xy 173.99 73.66) (xy 173.99 76.2)
		)
		(stroke
			(width 0)
			(type default)
		)
	)
	(wire
		(pts
			(xy 189.23 236.22) (xy 196.85 236.22)
		)
		(stroke
			(width 0)
			(type default)
		)
	)
	(bus
		(pts
			(xy 97.79 63.5) (xy 99.06 64.77)
		)
		(stroke
			(width 0)
			(type default)
		)
	)
	(wire
		(pts
			(xy 259.08 114.3) (xy 275.59 114.3)
		)
		(stroke
			(width 0)
			(type default)
		)
	)
	(wire
		(pts
			(xy 130.81 193.04) (xy 130.81 195.58)
		)
		(stroke
			(width 0)
			(type default)
		)
	)
	(wire
		(pts
			(xy 154.94 187.96) (xy 154.94 189.23)
		)
		(stroke
			(width 0)
			(type default)
		)
	)
	(bus
		(pts
			(xy 278.13 106.68) (xy 278.13 109.22)
		)
		(stroke
			(width 0)
			(type default)
		)
	)
	(wire
		(pts
			(xy 196.85 195.58) (xy 204.47 195.58)
		)
		(stroke
			(width 0)
			(type default)
		)
	)
	(wire
		(pts
			(xy 219.71 63.5) (xy 224.79 63.5)
		)
		(stroke
			(width 0)
			(type default)
		)
	)
	(wire
		(pts
			(xy 147.32 228.6) (xy 154.94 228.6)
		)
		(stroke
			(width 0)
			(type default)
		)
	)
	(bus
		(pts
			(xy 175.26 58.42) (xy 173.99 59.69)
		)
		(stroke
			(width 0)
			(type default)
		)
	)
	(bus
		(pts
			(xy 173.99 76.2) (xy 173.99 78.74)
		)
		(stroke
			(width 0)
			(type default)
		)
	)
	(wire
		(pts
			(xy 154.94 78.74) (xy 171.45 78.74)
		)
		(stroke
			(width 0)
			(type default)
		)
	)
	(wire
		(pts
			(xy 154.94 116.84) (xy 171.45 116.84)
		)
		(stroke
			(width 0)
			(type default)
		)
	)
	(wire
		(pts
			(xy 254 217.17) (xy 261.62 217.17)
		)
		(stroke
			(width 0)
			(type default)
		)
	)
	(wire
		(pts
			(xy 261.62 217.17) (xy 269.24 217.17)
		)
		(stroke
			(width 0)
			(type default)
		)
	)
	(wire
		(pts
			(xy 154.94 76.2) (xy 171.45 76.2)
		)
		(stroke
			(width 0)
			(type default)
		)
	)
	(wire
		(pts
			(xy 106.68 66.04) (xy 106.68 54.61)
		)
		(stroke
			(width 0)
			(type default)
		)
	)
	(bus
		(pts
			(xy 278.13 111.76) (xy 278.13 114.3)
		)
		(stroke
			(width 0)
			(type default)
		)
	)
	(wire
		(pts
			(xy 204.47 215.9) (xy 204.47 217.17)
		)
		(stroke
			(width 0)
			(type default)
		)
	)
	(wire
		(pts
			(xy 154.94 81.28) (xy 171.45 81.28)
		)
		(stroke
			(width 0)
			(type default)
		)
	)
	(bus
		(pts
			(xy 99.06 88.9) (xy 99.06 91.44)
		)
		(stroke
			(width 0)
			(type default)
		)
	)
	(wire
		(pts
			(xy 154.94 86.36) (xy 171.45 86.36)
		)
		(stroke
			(width 0)
			(type default)
		)
	)
	(bus
		(pts
			(xy 173.99 99.06) (xy 173.99 101.6)
		)
		(stroke
			(width 0)
			(type default)
		)
	)
	(wire
		(pts
			(xy 196.85 217.17) (xy 204.47 217.17)
		)
		(stroke
			(width 0)
			(type default)
		)
	)
	(bus
		(pts
			(xy 99.06 83.82) (xy 99.06 86.36)
		)
		(stroke
			(width 0)
			(type default)
		)
	)
	(wire
		(pts
			(xy 162.56 124.46) (xy 171.45 124.46)
		)
		(stroke
			(width 0)
			(type default)
		)
	)
	(bus
		(pts
			(xy 204.47 81.28) (xy 204.47 83.82)
		)
		(stroke
			(width 0)
			(type default)
		)
	)
	(wire
		(pts
			(xy 204.47 228.6) (xy 212.09 228.6)
		)
		(stroke
			(width 0)
			(type default)
		)
	)
	(bus
		(pts
			(xy 278.13 76.2) (xy 278.13 78.74)
		)
		(stroke
			(width 0)
			(type default)
		)
	)
	(bus
		(pts
			(xy 204.47 76.2) (xy 204.47 78.74)
		)
		(stroke
			(width 0)
			(type default)
		)
	)
	(wire
		(pts
			(xy 147.32 187.96) (xy 147.32 189.23)
		)
		(stroke
			(width 0)
			(type default)
		)
	)
	(wire
		(pts
			(xy 130.81 215.9) (xy 130.81 218.44)
		)
		(stroke
			(width 0)
			(type default)
		)
	)
	(bus
		(pts
			(xy 278.13 59.69) (xy 278.13 60.96)
		)
		(stroke
			(width 0)
			(type default)
		)
	)
	(wire
		(pts
			(xy 204.47 209.55) (xy 204.47 210.82)
		)
		(stroke
			(width 0)
			(type default)
		)
	)
	(bus
		(pts
			(xy 280.67 58.42) (xy 279.4 58.42)
		)
		(stroke
			(width 0)
			(type default)
		)
	)
	(wire
		(pts
			(xy 176.53 186.69) (xy 176.53 189.23)
		)
		(stroke
			(width 0)
			(type default)
		)
	)
	(bus
		(pts
			(xy 99.06 91.44) (xy 99.06 93.98)
		)
		(stroke
			(width 0)
			(type default)
		)
	)
	(wire
		(pts
			(xy 154.94 99.06) (xy 171.45 99.06)
		)
		(stroke
			(width 0)
			(type default)
		)
	)
	(bus
		(pts
			(xy 278.13 91.44) (xy 278.13 93.98)
		)
		(stroke
			(width 0)
			(type default)
		)
	)
	(wire
		(pts
			(xy 207.01 96.52) (xy 224.79 96.52)
		)
		(stroke
			(width 0)
			(type default)
		)
	)
	(bus
		(pts
			(xy 279.4 58.42) (xy 278.13 59.69)
		)
		(stroke
			(width 0)
			(type default)
		)
	)
	(wire
		(pts
			(xy 246.38 215.9) (xy 246.38 217.17)
		)
		(stroke
			(width 0)
			(type default)
		)
	)
	(wire
		(pts
			(xy 154.94 106.68) (xy 171.45 106.68)
		)
		(stroke
			(width 0)
			(type default)
		)
	)
	(wire
		(pts
			(xy 189.23 215.9) (xy 189.23 217.17)
		)
		(stroke
			(width 0)
			(type default)
		)
	)
	(bus
		(pts
			(xy 204.47 67.31) (xy 204.47 68.58)
		)
		(stroke
			(width 0)
			(type default)
		)
	)
	(wire
		(pts
			(xy 254 215.9) (xy 254 217.17)
		)
		(stroke
			(width 0)
			(type default)
		)
	)
	(wire
		(pts
			(xy 259.08 78.74) (xy 275.59 78.74)
		)
		(stroke
			(width 0)
			(type default)
		)
	)
	(wire
		(pts
			(xy 259.08 76.2) (xy 275.59 76.2)
		)
		(stroke
			(width 0)
			(type default)
		)
	)
	(wire
		(pts
			(xy 147.32 217.17) (xy 154.94 217.17)
		)
		(stroke
			(width 0)
			(type default)
		)
	)
	(polyline
		(pts
			(xy 119.38 179.07) (xy 119.38 175.26)
		)
		(stroke
			(width 0)
			(type default)
		)
	)
	(bus
		(pts
			(xy 99.06 93.98) (xy 99.06 96.52)
		)
		(stroke
			(width 0)
			(type default)
		)
	)
	(wire
		(pts
			(xy 255.27 187.96) (xy 262.89 187.96)
		)
		(stroke
			(width 0)
			(type default)
		)
	)
	(label "LPDDR4.DQ31"
		(at 275.59 111.76 180)
		(effects
			(font
				(size 1.27 1.27)
			)
			(justify right bottom)
		)
	)
	(label "LPDDR4.CA3_A"
		(at 207.01 76.2 0)
		(effects
			(font
				(size 1.27 1.27)
			)
			(justify left bottom)
		)
	)
	(label "LPDDR4.DMI2"
		(at 275.59 114.3 180)
		(effects
			(font
				(size 1.27 1.27)
			)
			(justify right bottom)
		)
	)
	(label "LPDDR4.ODT_CA_A"
		(at 101.6 88.9 0)
		(effects
			(font
				(size 1.27 1.27)
			)
			(justify left bottom)
		)
	)
	(label "LPDDR4.ODT_CA_A"
		(at 207.01 88.9 0)
		(effects
			(font
				(size 1.27 1.27)
			)
			(justify left bottom)
		)
	)
	(label "LPDDR4.CA0_A"
		(at 207.01 83.82 0)
		(effects
			(font
				(size 1.27 1.27)
			)
			(justify left bottom)
		)
	)
	(label "LPDDR4.DMI3"
		(at 275.59 116.84 180)
		(effects
			(font
				(size 1.27 1.27)
			)
			(justify right bottom)
		)
	)
	(label "LPDDR4.CK_N"
		(at 101.6 93.98 0)
		(effects
			(font
				(size 1.27 1.27)
			)
			(justify left bottom)
		)
	)
	(label "LPDDR4.DQ30"
		(at 275.59 109.22 180)
		(effects
			(font
				(size 1.27 1.27)
			)
			(justify right bottom)
		)
	)
	(label "LPDDR4.CKE0_A"
		(at 101.6 91.44 0)
		(effects
			(font
				(size 1.27 1.27)
			)
			(justify left bottom)
		)
	)
	(label "LPDDR4.DQ11"
		(at 171.45 101.6 180)
		(effects
			(font
				(size 1.27 1.27)
			)
			(justify right bottom)
		)
	)
	(label "LPDDR4.DQS0_P"
		(at 171.45 66.04 180)
		(effects
			(font
				(size 1.27 1.27)
			)
			(justify right bottom)
		)
	)
	(label "LPDDR4.CK_N"
		(at 207.01 93.98 0)
		(effects
			(font
				(size 1.27 1.27)
			)
			(justify left bottom)
		)
	)
	(label "LPDDR4.RESET_n"
		(at 101.6 99.06 0)
		(effects
			(font
				(size 1.27 1.27)
			)
			(justify left bottom)
		)
	)
	(label "LPDDR4.CS0_A"
		(at 207.01 86.36 0)
		(effects
			(font
				(size 1.27 1.27)
			)
			(justify left bottom)
		)
	)
	(label "LPDDR4.DQ9"
		(at 171.45 96.52 180)
		(effects
			(font
				(size 1.27 1.27)
			)
			(justify right bottom)
		)
	)
	(label "LPDDR4.DQ0"
		(at 171.45 73.66 180)
		(effects
			(font
				(size 1.27 1.27)
			)
			(justify right bottom)
		)
	)
	(label "LPDDR4.DQ18"
		(at 275.59 78.74 180)
		(effects
			(font
				(size 1.27 1.27)
			)
			(justify right bottom)
		)
	)
	(label "LPDDR4.CA2_A"
		(at 101.6 78.74 0)
		(effects
			(font
				(size 1.27 1.27)
			)
			(justify left bottom)
		)
	)
	(label "LPDDR4.DQ26"
		(at 275.59 99.06 180)
		(effects
			(font
				(size 1.27 1.27)
			)
			(justify right bottom)
		)
	)
	(label "LPDDR4.DQ27"
		(at 275.59 101.6 180)
		(effects
			(font
				(size 1.27 1.27)
			)
			(justify right bottom)
		)
	)
	(label "LPDDR4.DQ28"
		(at 275.59 104.14 180)
		(effects
			(font
				(size 1.27 1.27)
			)
			(justify right bottom)
		)
	)
	(label "LPDDR4.DQS3_N"
		(at 275.59 68.58 180)
		(effects
			(font
				(size 1.27 1.27)
			)
			(justify right bottom)
		)
	)
	(label "LPDDR4.CA3_A"
		(at 101.6 76.2 0)
		(effects
			(font
				(size 1.27 1.27)
			)
			(justify left bottom)
		)
	)
	(label "LPDDR4.DQ19"
		(at 275.59 81.28 180)
		(effects
			(font
				(size 1.27 1.27)
			)
			(justify right bottom)
		)
	)
	(label "LPDDR4.DQ4"
		(at 171.45 83.82 180)
		(effects
			(font
				(size 1.27 1.27)
			)
			(justify right bottom)
		)
	)
	(label "LPDDR4.DQS2_N"
		(at 275.59 63.5 180)
		(effects
			(font
				(size 1.27 1.27)
			)
			(justify right bottom)
		)
	)
	(label "LPDDR4.CA1_A"
		(at 207.01 81.28 0)
		(effects
			(font
				(size 1.27 1.27)
			)
			(justify left bottom)
		)
	)
	(label "LPDDR4.CA4_A"
		(at 207.01 73.66 0)
		(effects
			(font
				(size 1.27 1.27)
			)
			(justify left bottom)
		)
	)
	(label "LPDDR4.CA1_A"
		(at 101.6 81.28 0)
		(effects
			(font
				(size 1.27 1.27)
			)
			(justify left bottom)
		)
	)
	(label "LPDDR4.CK_P"
		(at 207.01 96.52 0)
		(effects
			(font
				(size 1.27 1.27)
			)
			(justify left bottom)
		)
	)
	(label "LPDDR4.DQ15"
		(at 171.45 111.76 180)
		(effects
			(font
				(size 1.27 1.27)
			)
			(justify right bottom)
		)
	)
	(label "LPDDR4.DQ5"
		(at 171.45 86.36 180)
		(effects
			(font
				(size 1.27 1.27)
			)
			(justify right bottom)
		)
	)
	(label "LPDDR4.DQ10"
		(at 171.45 99.06 180)
		(effects
			(font
				(size 1.27 1.27)
			)
			(justify right bottom)
		)
	)
	(label "LPDDR4.CK_P"
		(at 101.6 96.52 0)
		(effects
			(font
				(size 1.27 1.27)
			)
			(justify left bottom)
		)
	)
	(label "LPDDR4.DQ23"
		(at 275.59 91.44 180)
		(effects
			(font
				(size 1.27 1.27)
			)
			(justify right bottom)
		)
	)
	(label "LPDDR4.DQ12"
		(at 171.45 104.14 180)
		(effects
			(font
				(size 1.27 1.27)
			)
			(justify right bottom)
		)
	)
	(label "LPDDR4.CS0_A"
		(at 101.6 86.36 0)
		(effects
			(font
				(size 1.27 1.27)
			)
			(justify left bottom)
		)
	)
	(label "LPDDR4.DQ6"
		(at 171.45 88.9 180)
		(effects
			(font
				(size 1.27 1.27)
			)
			(justify right bottom)
		)
	)
	(label "LPDDR4.DQ25"
		(at 275.59 96.52 180)
		(effects
			(font
				(size 1.27 1.27)
			)
			(justify right bottom)
		)
	)
	(label "LPDDR4.DQS0_N"
		(at 171.45 63.5 180)
		(effects
			(font
				(size 1.27 1.27)
			)
			(justify right bottom)
		)
	)
	(label "LPDDR4.DQ29"
		(at 275.59 106.68 180)
		(effects
			(font
				(size 1.27 1.27)
			)
			(justify right bottom)
		)
	)
	(label "LPDDR4.CA5_A"
		(at 101.6 71.12 0)
		(effects
			(font
				(size 1.27 1.27)
			)
			(justify left bottom)
		)
	)
	(label "LPDDR4.DMI0"
		(at 171.45 114.3 180)
		(effects
			(font
				(size 1.27 1.27)
			)
			(justify right bottom)
		)
	)
	(label "LPDDR4.DQ2"
		(at 171.45 78.74 180)
		(effects
			(font
				(size 1.27 1.27)
			)
			(justify right bottom)
		)
	)
	(label "LPDDR4.DMI1"
		(at 171.45 116.84 180)
		(effects
			(font
				(size 1.27 1.27)
			)
			(justify right bottom)
		)
	)
	(label "LPDDR4.DQ14"
		(at 171.45 109.22 180)
		(effects
			(font
				(size 1.27 1.27)
			)
			(justify right bottom)
		)
	)
	(label "LPDDR4.DQ8"
		(at 171.45 93.98 180)
		(effects
			(font
				(size 1.27 1.27)
			)
			(justify right bottom)
		)
	)
	(label "LPDDR4.CA2_A"
		(at 207.01 78.74 0)
		(effects
			(font
				(size 1.27 1.27)
			)
			(justify left bottom)
		)
	)
	(label "LPDDR4.DQ3"
		(at 171.45 81.28 180)
		(effects
			(font
				(size 1.27 1.27)
			)
			(justify right bottom)
		)
	)
	(label "LPDDR4.DQ13"
		(at 171.45 106.68 180)
		(effects
			(font
				(size 1.27 1.27)
			)
			(justify right bottom)
		)
	)
	(label "LPDDR4.DQ21"
		(at 275.59 86.36 180)
		(effects
			(font
				(size 1.27 1.27)
			)
			(justify right bottom)
		)
	)
	(label "LPDDR4.CA0_A"
		(at 101.6 83.82 0)
		(effects
			(font
				(size 1.27 1.27)
			)
			(justify left bottom)
		)
	)
	(label "LPDDR4.DQ20"
		(at 275.59 83.82 180)
		(effects
			(font
				(size 1.27 1.27)
			)
			(justify right bottom)
		)
	)
	(label "LPDDR4.CKE0_A"
		(at 207.01 91.44 0)
		(effects
			(font
				(size 1.27 1.27)
			)
			(justify left bottom)
		)
	)
	(label "LPDDR4.DQ17"
		(at 275.59 76.2 180)
		(effects
			(font
				(size 1.27 1.27)
			)
			(justify right bottom)
		)
	)
	(label "LPDDR4.CA5_A"
		(at 207.01 71.12 0)
		(effects
			(font
				(size 1.27 1.27)
			)
			(justify left bottom)
		)
	)
	(label "LPDDR4.DQS2_P"
		(at 275.59 66.04 180)
		(effects
			(font
				(size 1.27 1.27)
			)
			(justify right bottom)
		)
	)
	(label "LPDDR4.DQ7"
		(at 171.45 91.44 180)
		(effects
			(font
				(size 1.27 1.27)
			)
			(justify right bottom)
		)
	)
	(label "LPDDR4.DQS1_N"
		(at 171.45 68.58 180)
		(effects
			(font
				(size 1.27 1.27)
			)
			(justify right bottom)
		)
	)
	(label "LPDDR4.DQS1_P"
		(at 171.45 71.12 180)
		(effects
			(font
				(size 1.27 1.27)
			)
			(justify right bottom)
		)
	)
	(label "LPDDR4.DQ16"
		(at 275.59 73.66 180)
		(effects
			(font
				(size 1.27 1.27)
			)
			(justify right bottom)
		)
	)
	(label "LPDDR4.DQ24"
		(at 275.59 93.98 180)
		(effects
			(font
				(size 1.27 1.27)
			)
			(justify right bottom)
		)
	)
	(label "LPDDR4.CA4_A"
		(at 101.6 73.66 0)
		(effects
			(font
				(size 1.27 1.27)
			)
			(justify left bottom)
		)
	)
	(label "LPDDR4.DQ22"
		(at 275.59 88.9 180)
		(effects
			(font
				(size 1.27 1.27)
			)
			(justify right bottom)
		)
	)
	(label "LPDDR4.DQS3_P"
		(at 275.59 71.12 180)
		(effects
			(font
				(size 1.27 1.27)
			)
			(justify right bottom)
		)
	)
	(label "LPDDR4.DQ1"
		(at 171.45 76.2 180)
		(effects
			(font
				(size 1.27 1.27)
			)
			(justify right bottom)
		)
	)
	(hierarchical_label "LPDDR4{LPDDR4}"
		(shape input)
		(at 280.67 58.42 0)
		(effects
			(font
				(size 1.27 1.27)
			)
			(justify left)
		)
	)
	(hierarchical_label "LPDDR4{LPDDR4}"
		(shape input)
		(at 176.53 58.42 0)
		(effects
			(font
				(size 1.27 1.27)
			)
			(justify left)
		)
	)
	(hierarchical_label "LPDDR4{LPDDR4}"
		(shape input)
		(at 201.93 66.04 180)
		(effects
			(font
				(size 1.27 1.27)
			)
			(justify right)
		)
	)
	(hierarchical_label "LPDDR4{LPDDR4}"
		(shape input)
		(at 96.52 63.5 180)
		(effects
			(font
				(size 1.27 1.27)
			)
			(justify right)
		)
	)
	(symbol
		(lib_id "antmicropower:GND")
		(at 154.94 196.85 0)
		(unit 1)
		(exclude_from_sim no)
		(in_bom yes)
		(on_board yes)
		(dnp no)
		(property "Reference" "#PWR0129"
			(at 163.83 199.39 0)
			(effects
				(font
					(size 1.27 1.27)
					(thickness 0.15)
				)
				(justify left bottom)
				(hide yes)
			)
		)
		(property "Value" "GND"
			(at 154.94 201.295 0)
			(effects
				(font
					(size 1.27 1.27)
					(thickness 0.15)
				)
			)
		)
		(property "Footprint" ""
			(at 163.83 204.47 0)
			(effects
				(font
					(size 1.27 1.27)
					(thickness 0.15)
				)
				(justify left bottom)
				(hide yes)
			)
		)
		(property "Datasheet" ""
			(at 163.83 209.55 0)
			(effects
				(font
					(size 1.27 1.27)
					(thickness 0.15)
				)
				(justify left bottom)
				(hide yes)
			)
		)
		(property "Description" ""
			(at 154.94 196.85 0)
			(effects
				(font
					(size 1.27 1.27)
				)
				(hide yes)
			)
		)
		(property "Author" "Antmicro"
			(at 163.83 204.47 0)
			(effects
				(font
					(size 1.27 1.27)
					(thickness 0.15)
				)
				(justify left bottom)
				(hide yes)
			)
		)
		(property "License" "Apache-2.0"
			(at 163.83 207.01 0)
			(effects
				(font
					(size 1.27 1.27)
					(thickness 0.15)
				)
				(justify left bottom)
				(hide yes)
			)
		)
		(pin "1"
		)
		(instances
			(project "polarfire-som"
				(path ""
					(reference "#PWR0129")
					(unit 1)
				)
			)
		)
	)
	(symbol
		(lib_id "antmicroCapacitors0402:C_1u_0402")
		(at 189.23 234.95 90)
		(unit 1)
		(exclude_from_sim no)
		(in_bom yes)
		(on_board yes)
		(dnp no)
		(property "Reference" "C148"
			(at 190.5 229.87 90)
			(effects
				(font
					(size 1.27 1.27)
					(thickness 0.15)
				)
				(justify right bottom)
			)
		)
		(property "Value" "C_1u_0402"
			(at 199.39 214.63 0)
			(effects
				(font
					(size 1.27 1.27)
					(thickness 0.15)
				)
				(justify left bottom)
				(hide yes)
			)
		)
		(property "Footprint" "antmicro-footprints:C_0402_1005Metric"
			(at 201.93 214.63 0)
			(effects
				(font
					(size 1.27 1.27)
					(thickness 0.15)
				)
				(justify left bottom)
				(hide yes)
			)
		)
		(property "Datasheet" "https://product.tdk.com/en/search/capacitor/ceramic/mlcc/info?part_no=C1005X6S1A105K050BC"
			(at 204.47 214.63 0)
			(effects
				(font
					(size 1.27 1.27)
					(thickness 0.15)
				)
				(justify left bottom)
				(hide yes)
			)
		)
		(property "Description" "SMD Multilayer Ceramic Capacitor, 1 µF, 10 V, 0402 [1005 Metric], ± 10%, X6S, C"
			(at 189.23 234.95 0)
			(effects
				(font
					(size 1.27 1.27)
				)
				(hide yes)
			)
		)
		(property "MPN" "C1005X6S1A105K050BC"
			(at 207.01 214.63 0)
			(effects
				(font
					(size 1.27 1.27)
					(thickness 0.15)
				)
				(justify left bottom)
				(hide yes)
			)
		)
		(property "Manufacturer" "TDK"
			(at 209.55 214.63 0)
			(effects
				(font
					(size 1.27 1.27)
					(thickness 0.15)
				)
				(justify left bottom)
				(hide yes)
			)
		)
		(property "License" "Apache-2.0"
			(at 212.09 214.63 0)
			(effects
				(font
					(size 1.27 1.27)
					(thickness 0.15)
				)
				(justify left bottom)
				(hide yes)
			)
		)
		(property "Author" "Antmicro"
			(at 214.63 214.63 0)
			(effects
				(font
					(size 1.27 1.27)
					(thickness 0.15)
				)
				(justify left bottom)
				(hide yes)
			)
		)
		(property "Val" "1u"
			(at 194.31 232.41 90)
			(effects
				(font
					(size 1.27 1.27)
					(thickness 0.15)
				)
				(justify left bottom)
			)
		)
		(property "Voltage" "16V"
			(at 217.17 214.63 0)
			(effects
				(font
					(size 1.27 1.27)
				)
				(justify left bottom)
				(hide yes)
			)
		)
		(property "Dielectric" "X5R"
			(at 219.71 214.63 0)
			(effects
				(font
					(size 1.27 1.27)
				)
				(justify left bottom)
				(hide yes)
			)
		)
		(property "Public" ""
			(at 222.25 214.63 0)
			(effects
				(font
					(size 1.27 1.27)
				)
				(justify left bottom)
				(hide yes)
			)
		)
		(pin "1"
		)
		(pin "2"
		)
		(instances
			(project "polarfire-som"
				(path ""
					(reference "C148")
					(unit 1)
				)
			)
		)
	)
	(symbol
		(lib_id "antmicroCapacitors0402:C_1u_0402")
		(at 261.62 215.9 90)
		(unit 1)
		(exclude_from_sim no)
		(in_bom yes)
		(on_board yes)
		(dnp no)
		(property "Reference" "C162"
			(at 262.89 210.82 90)
			(effects
				(font
					(size 1.27 1.27)
					(thickness 0.15)
				)
				(justify right bottom)
			)
		)
		(property "Value" "C_1u_0402"
			(at 271.78 195.58 0)
			(effects
				(font
					(size 1.27 1.27)
					(thickness 0.15)
				)
				(justify left bottom)
				(hide yes)
			)
		)
		(property "Footprint" "antmicro-footprints:C_0402_1005Metric"
			(at 274.32 195.58 0)
			(effects
				(font
					(size 1.27 1.27)
					(thickness 0.15)
				)
				(justify left bottom)
				(hide yes)
			)
		)
		(property "Datasheet" "https://product.tdk.com/en/search/capacitor/ceramic/mlcc/info?part_no=C1005X6S1A105K050BC"
			(at 276.86 195.58 0)
			(effects
				(font
					(size 1.27 1.27)
					(thickness 0.15)
				)
				(justify left bottom)
				(hide yes)
			)
		)
		(property "Description" "SMD Multilayer Ceramic Capacitor, 1 µF, 10 V, 0402 [1005 Metric], ± 10%, X6S, C"
			(at 261.62 215.9 0)
			(effects
				(font
					(size 1.27 1.27)
				)
				(hide yes)
			)
		)
		(property "MPN" "C1005X6S1A105K050BC"
			(at 279.4 195.58 0)
			(effects
				(font
					(size 1.27 1.27)
					(thickness 0.15)
				)
				(justify left bottom)
				(hide yes)
			)
		)
		(property "Manufacturer" "TDK"
			(at 281.94 195.58 0)
			(effects
				(font
					(size 1.27 1.27)
					(thickness 0.15)
				)
				(justify left bottom)
				(hide yes)
			)
		)
		(property "License" "Apache-2.0"
			(at 284.48 195.58 0)
			(effects
				(font
					(size 1.27 1.27)
					(thickness 0.15)
				)
				(justify left bottom)
				(hide yes)
			)
		)
		(property "Author" "Antmicro"
			(at 287.02 195.58 0)
			(effects
				(font
					(size 1.27 1.27)
					(thickness 0.15)
				)
				(justify left bottom)
				(hide yes)
			)
		)
		(property "Val" "1u"
			(at 266.7 213.36 90)
			(effects
				(font
					(size 1.27 1.27)
					(thickness 0.15)
				)
				(justify left bottom)
			)
		)
		(property "Voltage" "16V"
			(at 289.56 195.58 0)
			(effects
				(font
					(size 1.27 1.27)
				)
				(justify left bottom)
				(hide yes)
			)
		)
		(property "Dielectric" "X5R"
			(at 292.1 195.58 0)
			(effects
				(font
					(size 1.27 1.27)
				)
				(justify left bottom)
				(hide yes)
			)
		)
		(property "Public" ""
			(at 294.64 195.58 0)
			(effects
				(font
					(size 1.27 1.27)
				)
				(justify left bottom)
				(hide yes)
			)
		)
		(pin "1"
		)
		(pin "2"
		)
		(instances
			(project "polarfire-som"
				(path ""
					(reference "C162")
					(unit 1)
				)
			)
		)
	)
	(symbol
		(lib_id "antmicroMemory:MT53D512M32D2_WFBGA")
		(at 224.79 63.5 0)
		(unit 2)
		(exclude_from_sim no)
		(in_bom yes)
		(on_board yes)
		(dnp no)
		(fields_autoplaced yes)
		(property "Reference" "U12"
			(at 241.935 55.88 0)
			(effects
				(font
					(size 1.27 1.27)
					(thickness 0.15)
				)
			)
		)
		(property "Value" "MT53D512M32D2_WFBGA"
			(at 273.05 73.66 0)
			(effects
				(font
					(size 1.27 1.27)
					(thickness 0.15)
				)
				(justify left bottom)
				(hide yes)
			)
		)
		(property "Footprint" "antmicro-footprints:BGA-200_10.0x14.5mm_Layout12x22_P0.80x0.65mm"
			(at 273.05 76.2 0)
			(effects
				(font
					(size 1.27 1.27)
					(thickness 0.15)
				)
				(justify left bottom)
				(hide yes)
			)
		)
		(property "Datasheet" "https://eu.mouser.com/datasheet/2/671/200b_z11m_non_auto_lpddr4_lpddr4x-3077547.pdf"
			(at 273.05 78.74 0)
			(effects
				(font
					(size 1.27 1.27)
					(thickness 0.15)
				)
				(justify left bottom)
				(hide yes)
			)
		)
		(property "Description" "LPDDR4 DRAM, 1GX32"
			(at 224.79 63.5 0)
			(effects
				(font
					(size 1.27 1.27)
				)
				(hide yes)
			)
		)
		(property "MPN" "MT53D512M32D2DS-053 WT:D TR"
			(at 241.935 58.42 0)
			(effects
				(font
					(size 1.27 1.27)
					(thickness 0.15)
				)
			)
		)
		(property "Manufacturer" "Micron Technology"
			(at 273.05 81.28 0)
			(effects
				(font
					(size 1.27 1.27)
					(thickness 0.15)
				)
				(justify left bottom)
				(hide yes)
			)
		)
		(property "VSD_class" "LPDDR4"
			(at 273.05 83.82 0)
			(effects
				(font
					(size 1.27 1.27)
					(thickness 0.15)
				)
				(justify left bottom)
				(hide yes)
			)
		)
		(property "Author" "Antmicro"
			(at 273.05 86.36 0)
			(effects
				(font
					(size 1.27 1.27)
					(thickness 0.15)
				)
				(justify left bottom)
				(hide yes)
			)
		)
		(property "License" "Apache-2.0"
			(at 273.05 88.9 0)
			(effects
				(font
					(size 1.27 1.27)
					(thickness 0.15)
				)
				(justify left bottom)
				(hide yes)
			)
		)
		(pin "A1"
		)
		(pin "A2"
		)
		(pin "A3"
		)
		(pin "A4"
		)
		(pin "A5"
		)
		(pin "A9"
		)
		(pin "B1"
		)
		(pin "B11"
		)
		(pin "B2"
		)
		(pin "B3"
		)
		(pin "B4"
		)
		(pin "B5"
		)
		(pin "B8"
		)
		(pin "B9"
		)
		(pin "C1"
		)
		(pin "C10"
		)
		(pin "C11"
		)
		(pin "C2"
		)
		(pin "C3"
		)
		(pin "C4"
		)
		(pin "C5"
		)
		(pin "C8"
		)
		(pin "C9"
		)
		(pin "D1"
		)
		(pin "D10"
		)
		(pin "D2"
		)
		(pin "D3"
		)
		(pin "D4"
		)
		(pin "D5"
		)
		(pin "D8"
		)
		(pin "D9"
		)
		(pin "E1"
		)
		(pin "E10"
		)
		(pin "E11"
		)
		(pin "E2"
		)
		(pin "E3"
		)
		(pin "E4"
		)
		(pin "E5"
		)
		(pin "E8"
		)
		(pin "E9"
		)
		(pin "F1"
		)
		(pin "F11"
		)
		(pin "F2"
		)
		(pin "F3"
		)
		(pin "F4"
		)
		(pin "F5"
		)
		(pin "F8"
		)
		(pin "F9"
		)
		(pin "G1"
		)
		(pin "G2"
		)
		(pin "G3"
		)
		(pin "G4"
		)
		(pin "G5"
		)
		(pin "G8"
		)
		(pin "G9"
		)
		(pin "H1"
		)
		(pin "H10"
		)
		(pin "H11"
		)
		(pin "H2"
		)
		(pin "H3"
		)
		(pin "H4"
		)
		(pin "H5"
		)
		(pin "H8"
		)
		(pin "H9"
		)
		(pin "J1"
		)
		(pin "J11"
		)
		(pin "J2"
		)
		(pin "J3"
		)
		(pin "J4"
		)
		(pin "J5"
		)
		(pin "J8"
		)
		(pin "J9"
		)
		(pin "K1"
		)
		(pin "K2"
		)
		(pin "K3"
		)
		(pin "K4"
		)
		(pin "K5"
		)
		(pin "K8"
		)
		(pin "K9"
		)
		(pin "N1"
		)
		(pin "N2"
		)
		(pin "N3"
		)
		(pin "N4"
		)
		(pin "N5"
		)
		(pin "N8"
		)
		(pin "N9"
		)
		(pin "P1"
		)
		(pin "P3"
		)
		(pin "P5"
		)
		(pin "R1"
		)
		(pin "R3"
		)
		(pin "R5"
		)
		(pin "R8"
		)
		(pin "T1"
		)
		(pin "T11"
		)
		(pin "T3"
		)
		(pin "T4"
		)
		(pin "T5"
		)
		(pin "T8"
		)
		(pin "T9"
		)
		(pin "U1"
		)
		(pin "A10"
		)
		(pin "A11"
		)
		(pin "A12"
		)
		(pin "A8"
		)
		(pin "AA1"
		)
		(pin "AA10"
		)
		(pin "AA11"
		)
		(pin "AA12"
		)
		(pin "AA2"
		)
		(pin "AA3"
		)
		(pin "AA4"
		)
		(pin "AA5"
		)
		(pin "AA8"
		)
		(pin "AA9"
		)
		(pin "AB1"
		)
		(pin "AB10"
		)
		(pin "AB11"
		)
		(pin "AB12"
		)
		(pin "AB2"
		)
		(pin "AB3"
		)
		(pin "AB4"
		)
		(pin "AB5"
		)
		(pin "AB8"
		)
		(pin "AB9"
		)
		(pin "B10"
		)
		(pin "B12"
		)
		(pin "C12"
		)
		(pin "D11"
		)
		(pin "D12"
		)
		(pin "E12"
		)
		(pin "F10"
		)
		(pin "F12"
		)
		(pin "G10"
		)
		(pin "G11"
		)
		(pin "G12"
		)
		(pin "H12"
		)
		(pin "J10"
		)
		(pin "J12"
		)
		(pin "K10"
		)
		(pin "K11"
		)
		(pin "K12"
		)
		(pin "N10"
		)
		(pin "N11"
		)
		(pin "N12"
		)
		(pin "P10"
		)
		(pin "P11"
		)
		(pin "P12"
		)
		(pin "P2"
		)
		(pin "P4"
		)
		(pin "P8"
		)
		(pin "P9"
		)
		(pin "R10"
		)
		(pin "R11"
		)
		(pin "R12"
		)
		(pin "R2"
		)
		(pin "R4"
		)
		(pin "R9"
		)
		(pin "T10"
		)
		(pin "T12"
		)
		(pin "T2"
		)
		(pin "U10"
		)
		(pin "U11"
		)
		(pin "U12"
		)
		(pin "U2"
		)
		(pin "U3"
		)
		(pin "U4"
		)
		(pin "U5"
		)
		(pin "U8"
		)
		(pin "U9"
		)
		(pin "V1"
		)
		(pin "V10"
		)
		(pin "V11"
		)
		(pin "V12"
		)
		(pin "V2"
		)
		(pin "V3"
		)
		(pin "V4"
		)
		(pin "V5"
		)
		(pin "V8"
		)
		(pin "V9"
		)
		(pin "W1"
		)
		(pin "W10"
		)
		(pin "W11"
		)
		(pin "W12"
		)
		(pin "W2"
		)
		(pin "W3"
		)
		(pin "W4"
		)
		(pin "W5"
		)
		(pin "W8"
		)
		(pin "W9"
		)
		(pin "Y1"
		)
		(pin "Y10"
		)
		(pin "Y11"
		)
		(pin "Y12"
		)
		(pin "Y2"
		)
		(pin "Y3"
		)
		(pin "Y4"
		)
		(pin "Y5"
		)
		(pin "Y8"
		)
		(pin "Y9"
		)
		(instances
			(project "polarfire-som"
				(path ""
					(reference "U12")
					(unit 2)
				)
			)
		)
	)
	(symbol
		(lib_id "antmicropower:+1V1")
		(at 187.96 186.69 0)
		(unit 1)
		(exclude_from_sim no)
		(in_bom yes)
		(on_board yes)
		(dnp no)
		(property "Reference" "#PWR0141"
			(at 187.96 190.5 0)
			(effects
				(font
					(size 1.27 1.27)
				)
				(hide yes)
			)
		)
		(property "Value" "+1V1"
			(at 187.96 182.88 0)
			(effects
				(font
					(size 1.27 1.27)
				)
			)
		)
		(property "Footprint" ""
			(at 187.96 186.69 0)
			(effects
				(font
					(size 1.27 1.27)
				)
				(hide yes)
			)
		)
		(property "Datasheet" ""
			(at 187.96 186.69 0)
			(effects
				(font
					(size 1.27 1.27)
				)
				(hide yes)
			)
		)
		(property "Description" ""
			(at 187.96 186.69 0)
			(effects
				(font
					(size 1.27 1.27)
				)
				(hide yes)
			)
		)
		(pin "1"
		)
		(instances
			(project "polarfire-som"
				(path ""
					(reference "#PWR0141")
					(unit 1)
				)
			)
		)
	)
	(symbol
		(lib_id "antmicroCapacitors0402:C_1u_0402")
		(at 212.09 234.95 90)
		(unit 1)
		(exclude_from_sim no)
		(in_bom yes)
		(on_board yes)
		(dnp no)
		(property "Reference" "C143"
			(at 213.36 229.87 90)
			(effects
				(font
					(size 1.27 1.27)
					(thickness 0.15)
				)
				(justify right bottom)
			)
		)
		(property "Value" "C_1u_0402"
			(at 222.25 214.63 0)
			(effects
				(font
					(size 1.27 1.27)
					(thickness 0.15)
				)
				(justify left bottom)
				(hide yes)
			)
		)
		(property "Footprint" "antmicro-footprints:C_0402_1005Metric"
			(at 224.79 214.63 0)
			(effects
				(font
					(size 1.27 1.27)
					(thickness 0.15)
				)
				(justify left bottom)
				(hide yes)
			)
		)
		(property "Datasheet" "https://product.tdk.com/en/search/capacitor/ceramic/mlcc/info?part_no=C1005X6S1A105K050BC"
			(at 227.33 214.63 0)
			(effects
				(font
					(size 1.27 1.27)
					(thickness 0.15)
				)
				(justify left bottom)
				(hide yes)
			)
		)
		(property "Description" "SMD Multilayer Ceramic Capacitor, 1 µF, 10 V, 0402 [1005 Metric], ± 10%, X6S, C"
			(at 212.09 234.95 0)
			(effects
				(font
					(size 1.27 1.27)
				)
				(hide yes)
			)
		)
		(property "MPN" "C1005X6S1A105K050BC"
			(at 229.87 214.63 0)
			(effects
				(font
					(size 1.27 1.27)
					(thickness 0.15)
				)
				(justify left bottom)
				(hide yes)
			)
		)
		(property "Manufacturer" "TDK"
			(at 232.41 214.63 0)
			(effects
				(font
					(size 1.27 1.27)
					(thickness 0.15)
				)
				(justify left bottom)
				(hide yes)
			)
		)
		(property "License" "Apache-2.0"
			(at 234.95 214.63 0)
			(effects
				(font
					(size 1.27 1.27)
					(thickness 0.15)
				)
				(justify left bottom)
				(hide yes)
			)
		)
		(property "Author" "Antmicro"
			(at 237.49 214.63 0)
			(effects
				(font
					(size 1.27 1.27)
					(thickness 0.15)
				)
				(justify left bottom)
				(hide yes)
			)
		)
		(property "Val" "1u"
			(at 217.17 232.41 90)
			(effects
				(font
					(size 1.27 1.27)
					(thickness 0.15)
				)
				(justify left bottom)
			)
		)
		(property "Voltage" "16V"
			(at 240.03 214.63 0)
			(effects
				(font
					(size 1.27 1.27)
				)
				(justify left bottom)
				(hide yes)
			)
		)
		(property "Dielectric" "X5R"
			(at 242.57 214.63 0)
			(effects
				(font
					(size 1.27 1.27)
				)
				(justify left bottom)
				(hide yes)
			)
		)
		(property "Public" ""
			(at 245.11 214.63 0)
			(effects
				(font
					(size 1.27 1.27)
				)
				(justify left bottom)
				(hide yes)
			)
		)
		(pin "1"
		)
		(pin "2"
		)
		(instances
			(project "polarfire-som"
				(path ""
					(reference "C143")
					(unit 1)
				)
			)
		)
	)
	(symbol
		(lib_id "antmicropower:GND")
		(at 154.94 237.49 0)
		(unit 1)
		(exclude_from_sim no)
		(in_bom yes)
		(on_board yes)
		(dnp no)
		(property "Reference" "#PWR0260"
			(at 163.83 240.03 0)
			(effects
				(font
					(size 1.27 1.27)
					(thickness 0.15)
				)
				(justify left bottom)
				(hide yes)
			)
		)
		(property "Value" "GND"
			(at 154.94 241.935 0)
			(effects
				(font
					(size 1.27 1.27)
					(thickness 0.15)
				)
			)
		)
		(property "Footprint" ""
			(at 163.83 245.11 0)
			(effects
				(font
					(size 1.27 1.27)
					(thickness 0.15)
				)
				(justify left bottom)
				(hide yes)
			)
		)
		(property "Datasheet" ""
			(at 163.83 250.19 0)
			(effects
				(font
					(size 1.27 1.27)
					(thickness 0.15)
				)
				(justify left bottom)
				(hide yes)
			)
		)
		(property "Description" ""
			(at 154.94 237.49 0)
			(effects
				(font
					(size 1.27 1.27)
				)
				(hide yes)
			)
		)
		(property "Author" "Antmicro"
			(at 163.83 245.11 0)
			(effects
				(font
					(size 1.27 1.27)
					(thickness 0.15)
				)
				(justify left bottom)
				(hide yes)
			)
		)
		(property "License" "Apache-2.0"
			(at 163.83 247.65 0)
			(effects
				(font
					(size 1.27 1.27)
					(thickness 0.15)
				)
				(justify left bottom)
				(hide yes)
			)
		)
		(pin "1"
		)
		(instances
			(project "polarfire-som"
				(path ""
					(reference "#PWR0260")
					(unit 1)
				)
			)
		)
	)
	(symbol
		(lib_id "antmicropower:+1V1")
		(at 238.76 208.28 0)
		(unit 1)
		(exclude_from_sim no)
		(in_bom yes)
		(on_board yes)
		(dnp no)
		(property "Reference" "#PWR0249"
			(at 238.76 212.09 0)
			(effects
				(font
					(size 1.27 1.27)
				)
				(hide yes)
			)
		)
		(property "Value" "+1V1"
			(at 238.76 204.47 0)
			(effects
				(font
					(size 1.27 1.27)
				)
			)
		)
		(property "Footprint" ""
			(at 238.76 208.28 0)
			(effects
				(font
					(size 1.27 1.27)
				)
				(hide yes)
			)
		)
		(property "Datasheet" ""
			(at 238.76 208.28 0)
			(effects
				(font
					(size 1.27 1.27)
				)
				(hide yes)
			)
		)
		(property "Description" ""
			(at 238.76 208.28 0)
			(effects
				(font
					(size 1.27 1.27)
				)
				(hide yes)
			)
		)
		(pin "1"
		)
		(instances
			(project "polarfire-som"
				(path ""
					(reference "#PWR0249")
					(unit 1)
				)
			)
		)
	)
	(symbol
		(lib_id "antmicroCapacitors0402:C_10u_0402")
		(at 176.53 194.31 90)
		(unit 1)
		(exclude_from_sim no)
		(in_bom yes)
		(on_board yes)
		(dnp no)
		(property "Reference" "C76"
			(at 177.8 189.23 90)
			(effects
				(font
					(size 1.27 1.27)
					(thickness 0.15)
				)
				(justify right bottom)
			)
		)
		(property "Value" "C_10u_0402"
			(at 186.69 173.99 0)
			(effects
				(font
					(size 1.27 1.27)
					(thickness 0.15)
				)
				(justify left bottom)
				(hide yes)
			)
		)
		(property "Footprint" "antmicro-footprints:C_0402_1005Metric"
			(at 189.23 173.99 0)
			(effects
				(font
					(size 1.27 1.27)
					(thickness 0.15)
				)
				(justify left bottom)
				(hide yes)
			)
		)
		(property "Datasheet" "https://www.yageo.com/en/Chart/Download/pdf/CC0402MRX5R5BB106"
			(at 191.77 173.99 0)
			(effects
				(font
					(size 1.27 1.27)
					(thickness 0.15)
				)
				(justify left bottom)
				(hide yes)
			)
		)
		(property "Description" "SMD Multilayer Ceramic Capacitor, 10 µF, 6.3 V, 0402 [1005 Metric], ± 20%, X5R, CC Series"
			(at 176.53 194.31 0)
			(effects
				(font
					(size 1.27 1.27)
				)
				(hide yes)
			)
		)
		(property "MPN" "CC0402MRX5R5BB106"
			(at 194.31 173.99 0)
			(effects
				(font
					(size 1.27 1.27)
					(thickness 0.15)
				)
				(justify left bottom)
				(hide yes)
			)
		)
		(property "Manufacturer" "YAGEO"
			(at 196.85 173.99 0)
			(effects
				(font
					(size 1.27 1.27)
					(thickness 0.15)
				)
				(justify left bottom)
				(hide yes)
			)
		)
		(property "License" "Apache-2.0"
			(at 199.39 173.99 0)
			(effects
				(font
					(size 1.27 1.27)
					(thickness 0.15)
				)
				(justify left bottom)
				(hide yes)
			)
		)
		(property "Author" "Antmicro"
			(at 201.93 173.99 0)
			(effects
				(font
					(size 1.27 1.27)
					(thickness 0.15)
				)
				(justify left bottom)
				(hide yes)
			)
		)
		(property "Val" "10u"
			(at 177.8 194.31 90)
			(effects
				(font
					(size 1.27 1.27)
					(thickness 0.15)
				)
				(justify right top)
			)
		)
		(property "Voltage" ""
			(at 204.47 173.99 0)
			(effects
				(font
					(size 1.27 1.27)
				)
				(justify left bottom)
				(hide yes)
			)
		)
		(property "Dielectric" ""
			(at 207.01 173.99 0)
			(effects
				(font
					(size 1.27 1.27)
				)
				(justify left bottom)
				(hide yes)
			)
		)
		(property "Public" ""
			(at 209.55 173.99 0)
			(effects
				(font
					(size 1.27 1.27)
				)
				(justify left bottom)
				(hide yes)
			)
		)
		(pin "1"
		)
		(pin "2"
		)
		(instances
			(project "polarfire-som"
				(path ""
					(reference "C76")
					(unit 1)
				)
			)
		)
	)
	(symbol
		(lib_id "antmicroCapacitors0402:C_1u_0402")
		(at 270.51 194.31 90)
		(unit 1)
		(exclude_from_sim no)
		(in_bom yes)
		(on_board yes)
		(dnp no)
		(property "Reference" "C168"
			(at 271.78 189.23 90)
			(effects
				(font
					(size 1.27 1.27)
					(thickness 0.15)
				)
				(justify right bottom)
			)
		)
		(property "Value" "C_1u_0402"
			(at 280.67 173.99 0)
			(effects
				(font
					(size 1.27 1.27)
					(thickness 0.15)
				)
				(justify left bottom)
				(hide yes)
			)
		)
		(property "Footprint" "antmicro-footprints:C_0402_1005Metric"
			(at 283.21 173.99 0)
			(effects
				(font
					(size 1.27 1.27)
					(thickness 0.15)
				)
				(justify left bottom)
				(hide yes)
			)
		)
		(property "Datasheet" "https://product.tdk.com/en/search/capacitor/ceramic/mlcc/info?part_no=C1005X6S1A105K050BC"
			(at 285.75 173.99 0)
			(effects
				(font
					(size 1.27 1.27)
					(thickness 0.15)
				)
				(justify left bottom)
				(hide yes)
			)
		)
		(property "Description" "SMD Multilayer Ceramic Capacitor, 1 µF, 10 V, 0402 [1005 Metric], ± 10%, X6S, C"
			(at 270.51 194.31 0)
			(effects
				(font
					(size 1.27 1.27)
				)
				(hide yes)
			)
		)
		(property "MPN" "C1005X6S1A105K050BC"
			(at 288.29 173.99 0)
			(effects
				(font
					(size 1.27 1.27)
					(thickness 0.15)
				)
				(justify left bottom)
				(hide yes)
			)
		)
		(property "Manufacturer" "TDK"
			(at 290.83 173.99 0)
			(effects
				(font
					(size 1.27 1.27)
					(thickness 0.15)
				)
				(justify left bottom)
				(hide yes)
			)
		)
		(property "License" "Apache-2.0"
			(at 293.37 173.99 0)
			(effects
				(font
					(size 1.27 1.27)
					(thickness 0.15)
				)
				(justify left bottom)
				(hide yes)
			)
		)
		(property "Author" "Antmicro"
			(at 295.91 173.99 0)
			(effects
				(font
					(size 1.27 1.27)
					(thickness 0.15)
				)
				(justify left bottom)
				(hide yes)
			)
		)
		(property "Val" "1u"
			(at 275.59 191.77 90)
			(effects
				(font
					(size 1.27 1.27)
					(thickness 0.15)
				)
				(justify left bottom)
			)
		)
		(property "Voltage" "16V"
			(at 298.45 173.99 0)
			(effects
				(font
					(size 1.27 1.27)
				)
				(justify left bottom)
				(hide yes)
			)
		)
		(property "Dielectric" "X5R"
			(at 300.99 173.99 0)
			(effects
				(font
					(size 1.27 1.27)
				)
				(justify left bottom)
				(hide yes)
			)
		)
		(property "Public" ""
			(at 303.53 173.99 0)
			(effects
				(font
					(size 1.27 1.27)
				)
				(justify left bottom)
				(hide yes)
			)
		)
		(pin "1"
		)
		(pin "2"
		)
		(instances
			(project "polarfire-som"
				(path ""
					(reference "C168")
					(unit 1)
				)
			)
		)
	)
	(symbol
		(lib_id "antmicroCapacitors0402:C_1u_0402")
		(at 262.89 194.31 90)
		(unit 1)
		(exclude_from_sim no)
		(in_bom yes)
		(on_board yes)
		(dnp no)
		(property "Reference" "C163"
			(at 264.16 189.23 90)
			(effects
				(font
					(size 1.27 1.27)
					(thickness 0.15)
				)
				(justify right bottom)
			)
		)
		(property "Value" "C_1u_0402"
			(at 273.05 173.99 0)
			(effects
				(font
					(size 1.27 1.27)
					(thickness 0.15)
				)
				(justify left bottom)
				(hide yes)
			)
		)
		(property "Footprint" "antmicro-footprints:C_0402_1005Metric"
			(at 275.59 173.99 0)
			(effects
				(font
					(size 1.27 1.27)
					(thickness 0.15)
				)
				(justify left bottom)
				(hide yes)
			)
		)
		(property "Datasheet" "https://product.tdk.com/en/search/capacitor/ceramic/mlcc/info?part_no=C1005X6S1A105K050BC"
			(at 278.13 173.99 0)
			(effects
				(font
					(size 1.27 1.27)
					(thickness 0.15)
				)
				(justify left bottom)
				(hide yes)
			)
		)
		(property "Description" "SMD Multilayer Ceramic Capacitor, 1 µF, 10 V, 0402 [1005 Metric], ± 10%, X6S, C"
			(at 262.89 194.31 0)
			(effects
				(font
					(size 1.27 1.27)
				)
				(hide yes)
			)
		)
		(property "MPN" "C1005X6S1A105K050BC"
			(at 280.67 173.99 0)
			(effects
				(font
					(size 1.27 1.27)
					(thickness 0.15)
				)
				(justify left bottom)
				(hide yes)
			)
		)
		(property "Manufacturer" "TDK"
			(at 283.21 173.99 0)
			(effects
				(font
					(size 1.27 1.27)
					(thickness 0.15)
				)
				(justify left bottom)
				(hide yes)
			)
		)
		(property "License" "Apache-2.0"
			(at 285.75 173.99 0)
			(effects
				(font
					(size 1.27 1.27)
					(thickness 0.15)
				)
				(justify left bottom)
				(hide yes)
			)
		)
		(property "Author" "Antmicro"
			(at 288.29 173.99 0)
			(effects
				(font
					(size 1.27 1.27)
					(thickness 0.15)
				)
				(justify left bottom)
				(hide yes)
			)
		)
		(property "Val" "1u"
			(at 267.97 191.77 90)
			(effects
				(font
					(size 1.27 1.27)
					(thickness 0.15)
				)
				(justify left bottom)
			)
		)
		(property "Voltage" "16V"
			(at 290.83 173.99 0)
			(effects
				(font
					(size 1.27 1.27)
				)
				(justify left bottom)
				(hide yes)
			)
		)
		(property "Dielectric" "X5R"
			(at 293.37 173.99 0)
			(effects
				(font
					(size 1.27 1.27)
				)
				(justify left bottom)
				(hide yes)
			)
		)
		(property "Public" ""
			(at 295.91 173.99 0)
			(effects
				(font
					(size 1.27 1.27)
				)
				(justify left bottom)
				(hide yes)
			)
		)
		(pin "1"
		)
		(pin "2"
		)
		(instances
			(project "polarfire-som"
				(path ""
					(reference "C163")
					(unit 1)
				)
			)
		)
	)
	(symbol
		(lib_id "antmicroResistors0402:R_240R_0402")
		(at 157.48 124.46 0)
		(unit 1)
		(exclude_from_sim no)
		(in_bom yes)
		(on_board yes)
		(dnp no)
		(property "Reference" "R76"
			(at 156.845 123.19 0)
			(effects
				(font
					(size 1.27 1.27)
					(thickness 0.15)
				)
			)
		)
		(property "Value" "R_240R_0402"
			(at 177.8 137.16 0)
			(effects
				(font
					(size 1.27 1.27)
					(thickness 0.15)
				)
				(justify left bottom)
				(hide yes)
			)
		)
		(property "Footprint" "antmicro-footprints:R_0402_1005Metric"
			(at 177.8 139.7 0)
			(effects
				(font
					(size 1.27 1.27)
					(thickness 0.15)
				)
				(justify left bottom)
				(hide yes)
			)
		)
		(property "Datasheet" "https://www.bourns.com/docs/product-datasheets/cr.pdf"
			(at 177.8 142.24 0)
			(effects
				(font
					(size 1.27 1.27)
					(thickness 0.15)
				)
				(justify left bottom)
				(hide yes)
			)
		)
		(property "Description" "SMD Chip Resistor, 240 ohm, ± 1%, 63 mW, 0402 [1005 Metric], Thick Film, General Purpose"
			(at 157.48 124.46 0)
			(effects
				(font
					(size 1.27 1.27)
				)
				(hide yes)
			)
		)
		(property "MPN" "CR0402-FX-2400GLF"
			(at 177.8 144.78 0)
			(effects
				(font
					(size 1.27 1.27)
					(thickness 0.15)
				)
				(justify left bottom)
				(hide yes)
			)
		)
		(property "Manufacturer" "Bourns"
			(at 177.8 147.32 0)
			(effects
				(font
					(size 1.27 1.27)
					(thickness 0.15)
				)
				(justify left bottom)
				(hide yes)
			)
		)
		(property "License" "Apache-2.0"
			(at 177.8 149.86 0)
			(effects
				(font
					(size 1.27 1.27)
					(thickness 0.15)
				)
				(justify left bottom)
				(hide yes)
			)
		)
		(property "Author" "Antmicro"
			(at 177.8 152.4 0)
			(effects
				(font
					(size 1.27 1.27)
					(thickness 0.15)
				)
				(justify left bottom)
				(hide yes)
			)
		)
		(property "Val" "240R"
			(at 165.1 123.19 0)
			(effects
				(font
					(size 1.27 1.27)
					(thickness 0.15)
				)
			)
		)
		(property "Tolerance" "1%"
			(at 177.8 134.62 0)
			(effects
				(font
					(size 1.27 1.27)
				)
				(justify left bottom)
				(hide yes)
			)
		)
		(property "Public" ""
			(at 177.8 154.94 0)
			(effects
				(font
					(size 1.27 1.27)
				)
				(justify left bottom)
				(hide yes)
			)
		)
		(pin "1"
		)
		(pin "2"
		)
		(instances
			(project "polarfire-som"
				(path ""
					(reference "R76")
					(unit 1)
				)
			)
		)
	)
	(symbol
		(lib_id "antmicroCapacitors0402:C_1u_0402")
		(at 204.47 215.9 90)
		(unit 1)
		(exclude_from_sim no)
		(in_bom yes)
		(on_board yes)
		(dnp no)
		(property "Reference" "C129"
			(at 205.74 210.82 90)
			(effects
				(font
					(size 1.27 1.27)
					(thickness 0.15)
				)
				(justify right bottom)
			)
		)
		(property "Value" "C_1u_0402"
			(at 214.63 195.58 0)
			(effects
				(font
					(size 1.27 1.27)
					(thickness 0.15)
				)
				(justify left bottom)
				(hide yes)
			)
		)
		(property "Footprint" "antmicro-footprints:C_0402_1005Metric"
			(at 217.17 195.58 0)
			(effects
				(font
					(size 1.27 1.27)
					(thickness 0.15)
				)
				(justify left bottom)
				(hide yes)
			)
		)
		(property "Datasheet" "https://product.tdk.com/en/search/capacitor/ceramic/mlcc/info?part_no=C1005X6S1A105K050BC"
			(at 219.71 195.58 0)
			(effects
				(font
					(size 1.27 1.27)
					(thickness 0.15)
				)
				(justify left bottom)
				(hide yes)
			)
		)
		(property "Description" "SMD Multilayer Ceramic Capacitor, 1 µF, 10 V, 0402 [1005 Metric], ± 10%, X6S, C"
			(at 204.47 215.9 0)
			(effects
				(font
					(size 1.27 1.27)
				)
				(hide yes)
			)
		)
		(property "MPN" "C1005X6S1A105K050BC"
			(at 222.25 195.58 0)
			(effects
				(font
					(size 1.27 1.27)
					(thickness 0.15)
				)
				(justify left bottom)
				(hide yes)
			)
		)
		(property "Manufacturer" "TDK"
			(at 224.79 195.58 0)
			(effects
				(font
					(size 1.27 1.27)
					(thickness 0.15)
				)
				(justify left bottom)
				(hide yes)
			)
		)
		(property "License" "Apache-2.0"
			(at 227.33 195.58 0)
			(effects
				(font
					(size 1.27 1.27)
					(thickness 0.15)
				)
				(justify left bottom)
				(hide yes)
			)
		)
		(property "Author" "Antmicro"
			(at 229.87 195.58 0)
			(effects
				(font
					(size 1.27 1.27)
					(thickness 0.15)
				)
				(justify left bottom)
				(hide yes)
			)
		)
		(property "Val" "1u"
			(at 209.55 213.36 90)
			(effects
				(font
					(size 1.27 1.27)
					(thickness 0.15)
				)
				(justify left bottom)
			)
		)
		(property "Voltage" "16V"
			(at 232.41 195.58 0)
			(effects
				(font
					(size 1.27 1.27)
				)
				(justify left bottom)
				(hide yes)
			)
		)
		(property "Dielectric" "X5R"
			(at 234.95 195.58 0)
			(effects
				(font
					(size 1.27 1.27)
				)
				(justify left bottom)
				(hide yes)
			)
		)
		(property "Public" ""
			(at 237.49 195.58 0)
			(effects
				(font
					(size 1.27 1.27)
				)
				(justify left bottom)
				(hide yes)
			)
		)
		(pin "1"
		)
		(pin "2"
		)
		(instances
			(project "polarfire-som"
				(path ""
					(reference "C129")
					(unit 1)
				)
			)
		)
	)
	(symbol
		(lib_id "antmicropower:+1V1")
		(at 189.23 208.28 0)
		(unit 1)
		(exclude_from_sim no)
		(in_bom yes)
		(on_board yes)
		(dnp no)
		(property "Reference" "#PWR0132"
			(at 189.23 212.09 0)
			(effects
				(font
					(size 1.27 1.27)
				)
				(hide yes)
			)
		)
		(property "Value" "+1V1"
			(at 189.23 204.47 0)
			(effects
				(font
					(size 1.27 1.27)
				)
			)
		)
		(property "Footprint" ""
			(at 189.23 208.28 0)
			(effects
				(font
					(size 1.27 1.27)
				)
				(hide yes)
			)
		)
		(property "Datasheet" ""
			(at 189.23 208.28 0)
			(effects
				(font
					(size 1.27 1.27)
				)
				(hide yes)
			)
		)
		(property "Description" ""
			(at 189.23 208.28 0)
			(effects
				(font
					(size 1.27 1.27)
				)
				(hide yes)
			)
		)
		(pin "1"
		)
		(instances
			(project "polarfire-som"
				(path ""
					(reference "#PWR0132")
					(unit 1)
				)
			)
		)
	)
	(symbol
		(lib_id "antmicroCapacitors0402:C_1u_0402")
		(at 269.24 215.9 90)
		(unit 1)
		(exclude_from_sim no)
		(in_bom yes)
		(on_board yes)
		(dnp no)
		(property "Reference" "C166"
			(at 270.51 210.82 90)
			(effects
				(font
					(size 1.27 1.27)
					(thickness 0.15)
				)
				(justify right bottom)
			)
		)
		(property "Value" "C_1u_0402"
			(at 279.4 195.58 0)
			(effects
				(font
					(size 1.27 1.27)
					(thickness 0.15)
				)
				(justify left bottom)
				(hide yes)
			)
		)
		(property "Footprint" "antmicro-footprints:C_0402_1005Metric"
			(at 281.94 195.58 0)
			(effects
				(font
					(size 1.27 1.27)
					(thickness 0.15)
				)
				(justify left bottom)
				(hide yes)
			)
		)
		(property "Datasheet" "https://product.tdk.com/en/search/capacitor/ceramic/mlcc/info?part_no=C1005X6S1A105K050BC"
			(at 284.48 195.58 0)
			(effects
				(font
					(size 1.27 1.27)
					(thickness 0.15)
				)
				(justify left bottom)
				(hide yes)
			)
		)
		(property "Description" "SMD Multilayer Ceramic Capacitor, 1 µF, 10 V, 0402 [1005 Metric], ± 10%, X6S, C"
			(at 269.24 215.9 0)
			(effects
				(font
					(size 1.27 1.27)
				)
				(hide yes)
			)
		)
		(property "MPN" "C1005X6S1A105K050BC"
			(at 287.02 195.58 0)
			(effects
				(font
					(size 1.27 1.27)
					(thickness 0.15)
				)
				(justify left bottom)
				(hide yes)
			)
		)
		(property "Manufacturer" "TDK"
			(at 289.56 195.58 0)
			(effects
				(font
					(size 1.27 1.27)
					(thickness 0.15)
				)
				(justify left bottom)
				(hide yes)
			)
		)
		(property "License" "Apache-2.0"
			(at 292.1 195.58 0)
			(effects
				(font
					(size 1.27 1.27)
					(thickness 0.15)
				)
				(justify left bottom)
				(hide yes)
			)
		)
		(property "Author" "Antmicro"
			(at 294.64 195.58 0)
			(effects
				(font
					(size 1.27 1.27)
					(thickness 0.15)
				)
				(justify left bottom)
				(hide yes)
			)
		)
		(property "Val" "1u"
			(at 274.32 213.36 90)
			(effects
				(font
					(size 1.27 1.27)
					(thickness 0.15)
				)
				(justify left bottom)
			)
		)
		(property "Voltage" "16V"
			(at 297.18 195.58 0)
			(effects
				(font
					(size 1.27 1.27)
				)
				(justify left bottom)
				(hide yes)
			)
		)
		(property "Dielectric" "X5R"
			(at 299.72 195.58 0)
			(effects
				(font
					(size 1.27 1.27)
				)
				(justify left bottom)
				(hide yes)
			)
		)
		(property "Public" ""
			(at 302.26 195.58 0)
			(effects
				(font
					(size 1.27 1.27)
				)
				(justify left bottom)
				(hide yes)
			)
		)
		(pin "1"
		)
		(pin "2"
		)
		(instances
			(project "polarfire-som"
				(path ""
					(reference "C166")
					(unit 1)
				)
			)
		)
	)
	(symbol
		(lib_id "antmicroCapacitors0402:C_1u_0402")
		(at 154.94 234.95 90)
		(unit 1)
		(exclude_from_sim no)
		(in_bom yes)
		(on_board yes)
		(dnp no)
		(property "Reference" "C124"
			(at 156.21 229.87 90)
			(effects
				(font
					(size 1.27 1.27)
					(thickness 0.15)
				)
				(justify right bottom)
			)
		)
		(property "Value" "C_1u_0402"
			(at 165.1 214.63 0)
			(effects
				(font
					(size 1.27 1.27)
					(thickness 0.15)
				)
				(justify left bottom)
				(hide yes)
			)
		)
		(property "Footprint" "antmicro-footprints:C_0402_1005Metric"
			(at 167.64 214.63 0)
			(effects
				(font
					(size 1.27 1.27)
					(thickness 0.15)
				)
				(justify left bottom)
				(hide yes)
			)
		)
		(property "Datasheet" "https://product.tdk.com/en/search/capacitor/ceramic/mlcc/info?part_no=C1005X6S1A105K050BC"
			(at 170.18 214.63 0)
			(effects
				(font
					(size 1.27 1.27)
					(thickness 0.15)
				)
				(justify left bottom)
				(hide yes)
			)
		)
		(property "Description" "SMD Multilayer Ceramic Capacitor, 1 µF, 10 V, 0402 [1005 Metric], ± 10%, X6S, C"
			(at 154.94 234.95 0)
			(effects
				(font
					(size 1.27 1.27)
				)
				(hide yes)
			)
		)
		(property "MPN" "C1005X6S1A105K050BC"
			(at 172.72 214.63 0)
			(effects
				(font
					(size 1.27 1.27)
					(thickness 0.15)
				)
				(justify left bottom)
				(hide yes)
			)
		)
		(property "Manufacturer" "TDK"
			(at 175.26 214.63 0)
			(effects
				(font
					(size 1.27 1.27)
					(thickness 0.15)
				)
				(justify left bottom)
				(hide yes)
			)
		)
		(property "License" "Apache-2.0"
			(at 177.8 214.63 0)
			(effects
				(font
					(size 1.27 1.27)
					(thickness 0.15)
				)
				(justify left bottom)
				(hide yes)
			)
		)
		(property "Author" "Antmicro"
			(at 180.34 214.63 0)
			(effects
				(font
					(size 1.27 1.27)
					(thickness 0.15)
				)
				(justify left bottom)
				(hide yes)
			)
		)
		(property "Val" "1u"
			(at 160.02 232.41 90)
			(effects
				(font
					(size 1.27 1.27)
					(thickness 0.15)
				)
				(justify left bottom)
			)
		)
		(property "Voltage" "16V"
			(at 182.88 214.63 0)
			(effects
				(font
					(size 1.27 1.27)
				)
				(justify left bottom)
				(hide yes)
			)
		)
		(property "Dielectric" "X5R"
			(at 185.42 214.63 0)
			(effects
				(font
					(size 1.27 1.27)
				)
				(justify left bottom)
				(hide yes)
			)
		)
		(property "Public" ""
			(at 187.96 214.63 0)
			(effects
				(font
					(size 1.27 1.27)
				)
				(justify left bottom)
				(hide yes)
			)
		)
		(pin "1"
		)
		(pin "2"
		)
		(instances
			(project "polarfire-som"
				(path ""
					(reference "C124")
					(unit 1)
				)
			)
		)
	)
	(symbol
		(lib_id "antmicropower:+1V8")
		(at 210.82 54.61 0)
		(unit 1)
		(exclude_from_sim no)
		(in_bom yes)
		(on_board yes)
		(dnp no)
		(property "Reference" "#PWR0136"
			(at 226.06 57.15 0)
			(effects
				(font
					(size 1.27 1.27)
					(thickness 0.15)
				)
				(justify left bottom)
				(hide yes)
			)
		)
		(property "Value" "+1V8"
			(at 210.82 50.8 0)
			(effects
				(font
					(size 1.27 1.27)
					(thickness 0.15)
				)
			)
		)
		(property "Footprint" ""
			(at 226.06 62.23 0)
			(effects
				(font
					(size 1.27 1.27)
					(thickness 0.15)
				)
				(justify left bottom)
				(hide yes)
			)
		)
		(property "Datasheet" ""
			(at 226.06 64.77 0)
			(effects
				(font
					(size 1.27 1.27)
					(thickness 0.15)
				)
				(justify left bottom)
				(hide yes)
			)
		)
		(property "Description" ""
			(at 210.82 54.61 0)
			(effects
				(font
					(size 1.27 1.27)
				)
				(hide yes)
			)
		)
		(property "Author" "Antmicro"
			(at 226.06 62.23 0)
			(effects
				(font
					(size 1.27 1.27)
					(thickness 0.15)
				)
				(justify left bottom)
				(hide yes)
			)
		)
		(property "License" "Apache-2.0"
			(at 226.06 64.77 0)
			(effects
				(font
					(size 1.27 1.27)
					(thickness 0.15)
				)
				(justify left bottom)
				(hide yes)
			)
		)
		(pin "1"
		)
		(instances
			(project "polarfire-som"
				(path ""
					(reference "#PWR0136")
					(unit 1)
				)
			)
		)
	)
	(symbol
		(lib_id "antmicropower:+1V1")
		(at 176.53 186.69 0)
		(unit 1)
		(exclude_from_sim no)
		(in_bom yes)
		(on_board yes)
		(dnp no)
		(property "Reference" "#PWR0263"
			(at 176.53 190.5 0)
			(effects
				(font
					(size 1.27 1.27)
				)
				(hide yes)
			)
		)
		(property "Value" "+1V1"
			(at 176.53 182.88 0)
			(effects
				(font
					(size 1.27 1.27)
				)
			)
		)
		(property "Footprint" ""
			(at 176.53 186.69 0)
			(effects
				(font
					(size 1.27 1.27)
				)
				(hide yes)
			)
		)
		(property "Datasheet" ""
			(at 176.53 186.69 0)
			(effects
				(font
					(size 1.27 1.27)
				)
				(hide yes)
			)
		)
		(property "Description" ""
			(at 176.53 186.69 0)
			(effects
				(font
					(size 1.27 1.27)
				)
				(hide yes)
			)
		)
		(pin "1"
		)
		(instances
			(project "polarfire-som"
				(path ""
					(reference "#PWR0263")
					(unit 1)
				)
			)
		)
	)
	(symbol
		(lib_id "antmicroCapacitors0402:C_10u_0402")
		(at 130.81 215.9 90)
		(unit 1)
		(exclude_from_sim no)
		(in_bom yes)
		(on_board yes)
		(dnp no)
		(property "Reference" "C265"
			(at 132.08 210.82 90)
			(effects
				(font
					(size 1.27 1.27)
					(thickness 0.15)
				)
				(justify right bottom)
			)
		)
		(property "Value" "C_10u_0402"
			(at 140.97 195.58 0)
			(effects
				(font
					(size 1.27 1.27)
					(thickness 0.15)
				)
				(justify left bottom)
				(hide yes)
			)
		)
		(property "Footprint" "antmicro-footprints:C_0402_1005Metric"
			(at 143.51 195.58 0)
			(effects
				(font
					(size 1.27 1.27)
					(thickness 0.15)
				)
				(justify left bottom)
				(hide yes)
			)
		)
		(property "Datasheet" "https://www.yageo.com/en/Chart/Download/pdf/CC0402MRX5R5BB106"
			(at 146.05 195.58 0)
			(effects
				(font
					(size 1.27 1.27)
					(thickness 0.15)
				)
				(justify left bottom)
				(hide yes)
			)
		)
		(property "Description" "SMD Multilayer Ceramic Capacitor, 10 µF, 6.3 V, 0402 [1005 Metric], ± 20%, X5R, CC Series"
			(at 130.81 215.9 0)
			(effects
				(font
					(size 1.27 1.27)
				)
				(hide yes)
			)
		)
		(property "MPN" "CC0402MRX5R5BB106"
			(at 148.59 195.58 0)
			(effects
				(font
					(size 1.27 1.27)
					(thickness 0.15)
				)
				(justify left bottom)
				(hide yes)
			)
		)
		(property "Manufacturer" "YAGEO"
			(at 151.13 195.58 0)
			(effects
				(font
					(size 1.27 1.27)
					(thickness 0.15)
				)
				(justify left bottom)
				(hide yes)
			)
		)
		(property "License" "Apache-2.0"
			(at 153.67 195.58 0)
			(effects
				(font
					(size 1.27 1.27)
					(thickness 0.15)
				)
				(justify left bottom)
				(hide yes)
			)
		)
		(property "Author" "Antmicro"
			(at 156.21 195.58 0)
			(effects
				(font
					(size 1.27 1.27)
					(thickness 0.15)
				)
				(justify left bottom)
				(hide yes)
			)
		)
		(property "Val" "10u"
			(at 132.08 215.9 90)
			(effects
				(font
					(size 1.27 1.27)
					(thickness 0.15)
				)
				(justify right top)
			)
		)
		(property "Voltage" ""
			(at 158.75 195.58 0)
			(effects
				(font
					(size 1.27 1.27)
				)
				(justify left bottom)
				(hide yes)
			)
		)
		(property "Dielectric" ""
			(at 161.29 195.58 0)
			(effects
				(font
					(size 1.27 1.27)
				)
				(justify left bottom)
				(hide yes)
			)
		)
		(property "Public" ""
			(at 163.83 195.58 0)
			(effects
				(font
					(size 1.27 1.27)
				)
				(justify left bottom)
				(hide yes)
			)
		)
		(pin "1"
		)
		(pin "2"
		)
		(instances
			(project "polarfire-som"
				(path ""
					(reference "C265")
					(unit 1)
				)
			)
		)
	)
	(symbol
		(lib_id "antmicropower:+1V1")
		(at 237.49 186.69 0)
		(unit 1)
		(exclude_from_sim no)
		(in_bom yes)
		(on_board yes)
		(dnp no)
		(property "Reference" "#PWR0291"
			(at 237.49 190.5 0)
			(effects
				(font
					(size 1.27 1.27)
				)
				(hide yes)
			)
		)
		(property "Value" "+1V1"
			(at 237.49 182.88 0)
			(effects
				(font
					(size 1.27 1.27)
				)
			)
		)
		(property "Footprint" ""
			(at 237.49 186.69 0)
			(effects
				(font
					(size 1.27 1.27)
				)
				(hide yes)
			)
		)
		(property "Datasheet" ""
			(at 237.49 186.69 0)
			(effects
				(font
					(size 1.27 1.27)
				)
				(hide yes)
			)
		)
		(property "Description" ""
			(at 237.49 186.69 0)
			(effects
				(font
					(size 1.27 1.27)
				)
				(hide yes)
			)
		)
		(pin "1"
		)
		(instances
			(project "polarfire-som"
				(path ""
					(reference "#PWR0291")
					(unit 1)
				)
			)
		)
	)
	(symbol
		(lib_id "antmicropower:+1V1")
		(at 176.53 208.28 0)
		(unit 1)
		(exclude_from_sim no)
		(in_bom yes)
		(on_board yes)
		(dnp no)
		(property "Reference" "#PWR0284"
			(at 176.53 212.09 0)
			(effects
				(font
					(size 1.27 1.27)
				)
				(hide yes)
			)
		)
		(property "Value" "+1V1"
			(at 176.53 204.47 0)
			(effects
				(font
					(size 1.27 1.27)
				)
			)
		)
		(property "Footprint" ""
			(at 176.53 208.28 0)
			(effects
				(font
					(size 1.27 1.27)
				)
				(hide yes)
			)
		)
		(property "Datasheet" ""
			(at 176.53 208.28 0)
			(effects
				(font
					(size 1.27 1.27)
				)
				(hide yes)
			)
		)
		(property "Description" ""
			(at 176.53 208.28 0)
			(effects
				(font
					(size 1.27 1.27)
				)
				(hide yes)
			)
		)
		(pin "1"
		)
		(instances
			(project "polarfire-som"
				(path ""
					(reference "#PWR0284")
					(unit 1)
				)
			)
		)
	)
	(symbol
		(lib_id "antmicroCapacitors0402:C_10u_0402")
		(at 237.49 194.31 90)
		(unit 1)
		(exclude_from_sim no)
		(in_bom yes)
		(on_board yes)
		(dnp no)
		(property "Reference" "C264"
			(at 238.76 189.23 90)
			(effects
				(font
					(size 1.27 1.27)
					(thickness 0.15)
				)
				(justify right bottom)
			)
		)
		(property "Value" "C_10u_0402"
			(at 247.65 173.99 0)
			(effects
				(font
					(size 1.27 1.27)
					(thickness 0.15)
				)
				(justify left bottom)
				(hide yes)
			)
		)
		(property "Footprint" "antmicro-footprints:C_0402_1005Metric"
			(at 250.19 173.99 0)
			(effects
				(font
					(size 1.27 1.27)
					(thickness 0.15)
				)
				(justify left bottom)
				(hide yes)
			)
		)
		(property "Datasheet" "https://www.yageo.com/en/Chart/Download/pdf/CC0402MRX5R5BB106"
			(at 252.73 173.99 0)
			(effects
				(font
					(size 1.27 1.27)
					(thickness 0.15)
				)
				(justify left bottom)
				(hide yes)
			)
		)
		(property "Description" "SMD Multilayer Ceramic Capacitor, 10 µF, 6.3 V, 0402 [1005 Metric], ± 20%, X5R, CC Series"
			(at 237.49 194.31 0)
			(effects
				(font
					(size 1.27 1.27)
				)
				(hide yes)
			)
		)
		(property "MPN" "CC0402MRX5R5BB106"
			(at 255.27 173.99 0)
			(effects
				(font
					(size 1.27 1.27)
					(thickness 0.15)
				)
				(justify left bottom)
				(hide yes)
			)
		)
		(property "Manufacturer" "YAGEO"
			(at 257.81 173.99 0)
			(effects
				(font
					(size 1.27 1.27)
					(thickness 0.15)
				)
				(justify left bottom)
				(hide yes)
			)
		)
		(property "License" "Apache-2.0"
			(at 260.35 173.99 0)
			(effects
				(font
					(size 1.27 1.27)
					(thickness 0.15)
				)
				(justify left bottom)
				(hide yes)
			)
		)
		(property "Author" "Antmicro"
			(at 262.89 173.99 0)
			(effects
				(font
					(size 1.27 1.27)
					(thickness 0.15)
				)
				(justify left bottom)
				(hide yes)
			)
		)
		(property "Val" "10u"
			(at 238.76 194.31 90)
			(effects
				(font
					(size 1.27 1.27)
					(thickness 0.15)
				)
				(justify right top)
			)
		)
		(property "Voltage" ""
			(at 265.43 173.99 0)
			(effects
				(font
					(size 1.27 1.27)
				)
				(justify left bottom)
				(hide yes)
			)
		)
		(property "Dielectric" ""
			(at 267.97 173.99 0)
			(effects
				(font
					(size 1.27 1.27)
				)
				(justify left bottom)
				(hide yes)
			)
		)
		(property "Public" ""
			(at 270.51 173.99 0)
			(effects
				(font
					(size 1.27 1.27)
				)
				(justify left bottom)
				(hide yes)
			)
		)
		(pin "1"
		)
		(pin "2"
		)
		(instances
			(project "polarfire-som"
				(path ""
					(reference "C264")
					(unit 1)
				)
			)
		)
	)
	(symbol
		(lib_id "antmicropower:GND")
		(at 212.09 218.44 0)
		(unit 1)
		(exclude_from_sim no)
		(in_bom yes)
		(on_board yes)
		(dnp no)
		(property "Reference" "#PWR0134"
			(at 220.98 220.98 0)
			(effects
				(font
					(size 1.27 1.27)
					(thickness 0.15)
				)
				(justify left bottom)
				(hide yes)
			)
		)
		(property "Value" "GND"
			(at 212.09 222.885 0)
			(effects
				(font
					(size 1.27 1.27)
					(thickness 0.15)
				)
			)
		)
		(property "Footprint" ""
			(at 220.98 226.06 0)
			(effects
				(font
					(size 1.27 1.27)
					(thickness 0.15)
				)
				(justify left bottom)
				(hide yes)
			)
		)
		(property "Datasheet" ""
			(at 220.98 231.14 0)
			(effects
				(font
					(size 1.27 1.27)
					(thickness 0.15)
				)
				(justify left bottom)
				(hide yes)
			)
		)
		(property "Description" ""
			(at 212.09 218.44 0)
			(effects
				(font
					(size 1.27 1.27)
				)
				(hide yes)
			)
		)
		(property "Author" "Antmicro"
			(at 220.98 226.06 0)
			(effects
				(font
					(size 1.27 1.27)
					(thickness 0.15)
				)
				(justify left bottom)
				(hide yes)
			)
		)
		(property "License" "Apache-2.0"
			(at 220.98 228.6 0)
			(effects
				(font
					(size 1.27 1.27)
					(thickness 0.15)
				)
				(justify left bottom)
				(hide yes)
			)
		)
		(pin "1"
		)
		(instances
			(project "polarfire-som"
				(path ""
					(reference "#PWR0134")
					(unit 1)
				)
			)
		)
	)
	(symbol
		(lib_id "antmicroCapacitors0402:C_1u_0402")
		(at 254 215.9 90)
		(unit 1)
		(exclude_from_sim no)
		(in_bom yes)
		(on_board yes)
		(dnp no)
		(property "Reference" "C158"
			(at 255.27 210.82 90)
			(effects
				(font
					(size 1.27 1.27)
					(thickness 0.15)
				)
				(justify right bottom)
			)
		)
		(property "Value" "C_1u_0402"
			(at 264.16 195.58 0)
			(effects
				(font
					(size 1.27 1.27)
					(thickness 0.15)
				)
				(justify left bottom)
				(hide yes)
			)
		)
		(property "Footprint" "antmicro-footprints:C_0402_1005Metric"
			(at 266.7 195.58 0)
			(effects
				(font
					(size 1.27 1.27)
					(thickness 0.15)
				)
				(justify left bottom)
				(hide yes)
			)
		)
		(property "Datasheet" "https://product.tdk.com/en/search/capacitor/ceramic/mlcc/info?part_no=C1005X6S1A105K050BC"
			(at 269.24 195.58 0)
			(effects
				(font
					(size 1.27 1.27)
					(thickness 0.15)
				)
				(justify left bottom)
				(hide yes)
			)
		)
		(property "Description" "SMD Multilayer Ceramic Capacitor, 1 µF, 10 V, 0402 [1005 Metric], ± 10%, X6S, C"
			(at 254 215.9 0)
			(effects
				(font
					(size 1.27 1.27)
				)
				(hide yes)
			)
		)
		(property "MPN" "C1005X6S1A105K050BC"
			(at 271.78 195.58 0)
			(effects
				(font
					(size 1.27 1.27)
					(thickness 0.15)
				)
				(justify left bottom)
				(hide yes)
			)
		)
		(property "Manufacturer" "TDK"
			(at 274.32 195.58 0)
			(effects
				(font
					(size 1.27 1.27)
					(thickness 0.15)
				)
				(justify left bottom)
				(hide yes)
			)
		)
		(property "License" "Apache-2.0"
			(at 276.86 195.58 0)
			(effects
				(font
					(size 1.27 1.27)
					(thickness 0.15)
				)
				(justify left bottom)
				(hide yes)
			)
		)
		(property "Author" "Antmicro"
			(at 279.4 195.58 0)
			(effects
				(font
					(size 1.27 1.27)
					(thickness 0.15)
				)
				(justify left bottom)
				(hide yes)
			)
		)
		(property "Val" "1u"
			(at 259.08 213.36 90)
			(effects
				(font
					(size 1.27 1.27)
					(thickness 0.15)
				)
				(justify left bottom)
			)
		)
		(property "Voltage" "16V"
			(at 281.94 195.58 0)
			(effects
				(font
					(size 1.27 1.27)
				)
				(justify left bottom)
				(hide yes)
			)
		)
		(property "Dielectric" "X5R"
			(at 284.48 195.58 0)
			(effects
				(font
					(size 1.27 1.27)
				)
				(justify left bottom)
				(hide yes)
			)
		)
		(property "Public" ""
			(at 287.02 195.58 0)
			(effects
				(font
					(size 1.27 1.27)
				)
				(justify left bottom)
				(hide yes)
			)
		)
		(pin "1"
		)
		(pin "2"
		)
		(instances
			(project "polarfire-som"
				(path ""
					(reference "C158")
					(unit 1)
				)
			)
		)
	)
	(symbol
		(lib_id "antmicroCapacitors0402:C_1u_0402")
		(at 238.76 215.9 90)
		(unit 1)
		(exclude_from_sim no)
		(in_bom yes)
		(on_board yes)
		(dnp no)
		(property "Reference" "C150"
			(at 240.03 210.82 90)
			(effects
				(font
					(size 1.27 1.27)
					(thickness 0.15)
				)
				(justify right bottom)
			)
		)
		(property "Value" "C_1u_0402"
			(at 248.92 195.58 0)
			(effects
				(font
					(size 1.27 1.27)
					(thickness 0.15)
				)
				(justify left bottom)
				(hide yes)
			)
		)
		(property "Footprint" "antmicro-footprints:C_0402_1005Metric"
			(at 251.46 195.58 0)
			(effects
				(font
					(size 1.27 1.27)
					(thickness 0.15)
				)
				(justify left bottom)
				(hide yes)
			)
		)
		(property "Datasheet" "https://product.tdk.com/en/search/capacitor/ceramic/mlcc/info?part_no=C1005X6S1A105K050BC"
			(at 254 195.58 0)
			(effects
				(font
					(size 1.27 1.27)
					(thickness 0.15)
				)
				(justify left bottom)
				(hide yes)
			)
		)
		(property "Description" "SMD Multilayer Ceramic Capacitor, 1 µF, 10 V, 0402 [1005 Metric], ± 10%, X6S, C"
			(at 238.76 215.9 0)
			(effects
				(font
					(size 1.27 1.27)
				)
				(hide yes)
			)
		)
		(property "MPN" "C1005X6S1A105K050BC"
			(at 256.54 195.58 0)
			(effects
				(font
					(size 1.27 1.27)
					(thickness 0.15)
				)
				(justify left bottom)
				(hide yes)
			)
		)
		(property "Manufacturer" "TDK"
			(at 259.08 195.58 0)
			(effects
				(font
					(size 1.27 1.27)
					(thickness 0.15)
				)
				(justify left bottom)
				(hide yes)
			)
		)
		(property "License" "Apache-2.0"
			(at 261.62 195.58 0)
			(effects
				(font
					(size 1.27 1.27)
					(thickness 0.15)
				)
				(justify left bottom)
				(hide yes)
			)
		)
		(property "Author" "Antmicro"
			(at 264.16 195.58 0)
			(effects
				(font
					(size 1.27 1.27)
					(thickness 0.15)
				)
				(justify left bottom)
				(hide yes)
			)
		)
		(property "Val" "1u"
			(at 243.84 213.36 90)
			(effects
				(font
					(size 1.27 1.27)
					(thickness 0.15)
				)
				(justify left bottom)
			)
		)
		(property "Voltage" "16V"
			(at 266.7 195.58 0)
			(effects
				(font
					(size 1.27 1.27)
				)
				(justify left bottom)
				(hide yes)
			)
		)
		(property "Dielectric" "X5R"
			(at 269.24 195.58 0)
			(effects
				(font
					(size 1.27 1.27)
				)
				(justify left bottom)
				(hide yes)
			)
		)
		(property "Public" ""
			(at 271.78 195.58 0)
			(effects
				(font
					(size 1.27 1.27)
				)
				(justify left bottom)
				(hide yes)
			)
		)
		(pin "1"
		)
		(pin "2"
		)
		(instances
			(project "polarfire-som"
				(path ""
					(reference "C150")
					(unit 1)
				)
			)
		)
	)
	(symbol
		(lib_id "antmicroCapacitors0402:C_1u_0402")
		(at 212.09 215.9 90)
		(unit 1)
		(exclude_from_sim no)
		(in_bom yes)
		(on_board yes)
		(dnp no)
		(property "Reference" "C135"
			(at 213.36 210.82 90)
			(effects
				(font
					(size 1.27 1.27)
					(thickness 0.15)
				)
				(justify right bottom)
			)
		)
		(property "Value" "C_1u_0402"
			(at 222.25 195.58 0)
			(effects
				(font
					(size 1.27 1.27)
					(thickness 0.15)
				)
				(justify left bottom)
				(hide yes)
			)
		)
		(property "Footprint" "antmicro-footprints:C_0402_1005Metric"
			(at 224.79 195.58 0)
			(effects
				(font
					(size 1.27 1.27)
					(thickness 0.15)
				)
				(justify left bottom)
				(hide yes)
			)
		)
		(property "Datasheet" "https://product.tdk.com/en/search/capacitor/ceramic/mlcc/info?part_no=C1005X6S1A105K050BC"
			(at 227.33 195.58 0)
			(effects
				(font
					(size 1.27 1.27)
					(thickness 0.15)
				)
				(justify left bottom)
				(hide yes)
			)
		)
		(property "Description" "SMD Multilayer Ceramic Capacitor, 1 µF, 10 V, 0402 [1005 Metric], ± 10%, X6S, C"
			(at 212.09 215.9 0)
			(effects
				(font
					(size 1.27 1.27)
				)
				(hide yes)
			)
		)
		(property "MPN" "C1005X6S1A105K050BC"
			(at 229.87 195.58 0)
			(effects
				(font
					(size 1.27 1.27)
					(thickness 0.15)
				)
				(justify left bottom)
				(hide yes)
			)
		)
		(property "Manufacturer" "TDK"
			(at 232.41 195.58 0)
			(effects
				(font
					(size 1.27 1.27)
					(thickness 0.15)
				)
				(justify left bottom)
				(hide yes)
			)
		)
		(property "License" "Apache-2.0"
			(at 234.95 195.58 0)
			(effects
				(font
					(size 1.27 1.27)
					(thickness 0.15)
				)
				(justify left bottom)
				(hide yes)
			)
		)
		(property "Author" "Antmicro"
			(at 237.49 195.58 0)
			(effects
				(font
					(size 1.27 1.27)
					(thickness 0.15)
				)
				(justify left bottom)
				(hide yes)
			)
		)
		(property "Val" "1u"
			(at 217.17 213.36 90)
			(effects
				(font
					(size 1.27 1.27)
					(thickness 0.15)
				)
				(justify left bottom)
			)
		)
		(property "Voltage" "16V"
			(at 240.03 195.58 0)
			(effects
				(font
					(size 1.27 1.27)
				)
				(justify left bottom)
				(hide yes)
			)
		)
		(property "Dielectric" "X5R"
			(at 242.57 195.58 0)
			(effects
				(font
					(size 1.27 1.27)
				)
				(justify left bottom)
				(hide yes)
			)
		)
		(property "Public" ""
			(at 245.11 195.58 0)
			(effects
				(font
					(size 1.27 1.27)
				)
				(justify left bottom)
				(hide yes)
			)
		)
		(pin "1"
		)
		(pin "2"
		)
		(instances
			(project "polarfire-som"
				(path ""
					(reference "C135")
					(unit 1)
				)
			)
		)
	)
	(symbol
		(lib_id "antmicroCapacitors0402:C_1u_0402")
		(at 255.27 194.31 90)
		(unit 1)
		(exclude_from_sim no)
		(in_bom yes)
		(on_board yes)
		(dnp no)
		(property "Reference" "C159"
			(at 256.54 189.23 90)
			(effects
				(font
					(size 1.27 1.27)
					(thickness 0.15)
				)
				(justify right bottom)
			)
		)
		(property "Value" "C_1u_0402"
			(at 265.43 173.99 0)
			(effects
				(font
					(size 1.27 1.27)
					(thickness 0.15)
				)
				(justify left bottom)
				(hide yes)
			)
		)
		(property "Footprint" "antmicro-footprints:C_0402_1005Metric"
			(at 267.97 173.99 0)
			(effects
				(font
					(size 1.27 1.27)
					(thickness 0.15)
				)
				(justify left bottom)
				(hide yes)
			)
		)
		(property "Datasheet" "https://product.tdk.com/en/search/capacitor/ceramic/mlcc/info?part_no=C1005X6S1A105K050BC"
			(at 270.51 173.99 0)
			(effects
				(font
					(size 1.27 1.27)
					(thickness 0.15)
				)
				(justify left bottom)
				(hide yes)
			)
		)
		(property "Description" "SMD Multilayer Ceramic Capacitor, 1 µF, 10 V, 0402 [1005 Metric], ± 10%, X6S, C"
			(at 255.27 194.31 0)
			(effects
				(font
					(size 1.27 1.27)
				)
				(hide yes)
			)
		)
		(property "MPN" "C1005X6S1A105K050BC"
			(at 273.05 173.99 0)
			(effects
				(font
					(size 1.27 1.27)
					(thickness 0.15)
				)
				(justify left bottom)
				(hide yes)
			)
		)
		(property "Manufacturer" "TDK"
			(at 275.59 173.99 0)
			(effects
				(font
					(size 1.27 1.27)
					(thickness 0.15)
				)
				(justify left bottom)
				(hide yes)
			)
		)
		(property "License" "Apache-2.0"
			(at 278.13 173.99 0)
			(effects
				(font
					(size 1.27 1.27)
					(thickness 0.15)
				)
				(justify left bottom)
				(hide yes)
			)
		)
		(property "Author" "Antmicro"
			(at 280.67 173.99 0)
			(effects
				(font
					(size 1.27 1.27)
					(thickness 0.15)
				)
				(justify left bottom)
				(hide yes)
			)
		)
		(property "Val" "1u"
			(at 260.35 191.77 90)
			(effects
				(font
					(size 1.27 1.27)
					(thickness 0.15)
				)
				(justify left bottom)
			)
		)
		(property "Voltage" "16V"
			(at 283.21 173.99 0)
			(effects
				(font
					(size 1.27 1.27)
				)
				(justify left bottom)
				(hide yes)
			)
		)
		(property "Dielectric" "X5R"
			(at 285.75 173.99 0)
			(effects
				(font
					(size 1.27 1.27)
				)
				(justify left bottom)
				(hide yes)
			)
		)
		(property "Public" ""
			(at 288.29 173.99 0)
			(effects
				(font
					(size 1.27 1.27)
				)
				(justify left bottom)
				(hide yes)
			)
		)
		(pin "1"
		)
		(pin "2"
		)
		(instances
			(project "polarfire-som"
				(path ""
					(reference "C159")
					(unit 1)
				)
			)
		)
	)
	(symbol
		(lib_id "antmicropower:+1V8")
		(at 147.32 208.28 0)
		(unit 1)
		(exclude_from_sim no)
		(in_bom yes)
		(on_board yes)
		(dnp no)
		(property "Reference" "#PWR0117"
			(at 162.56 210.82 0)
			(effects
				(font
					(size 1.27 1.27)
					(thickness 0.15)
				)
				(justify left bottom)
				(hide yes)
			)
		)
		(property "Value" "+1V8"
			(at 147.32 204.47 0)
			(effects
				(font
					(size 1.27 1.27)
					(thickness 0.15)
				)
			)
		)
		(property "Footprint" ""
			(at 162.56 215.9 0)
			(effects
				(font
					(size 1.27 1.27)
					(thickness 0.15)
				)
				(justify left bottom)
				(hide yes)
			)
		)
		(property "Datasheet" ""
			(at 162.56 218.44 0)
			(effects
				(font
					(size 1.27 1.27)
					(thickness 0.15)
				)
				(justify left bottom)
				(hide yes)
			)
		)
		(property "Description" ""
			(at 147.32 208.28 0)
			(effects
				(font
					(size 1.27 1.27)
				)
				(hide yes)
			)
		)
		(property "Author" "Antmicro"
			(at 162.56 215.9 0)
			(effects
				(font
					(size 1.27 1.27)
					(thickness 0.15)
				)
				(justify left bottom)
				(hide yes)
			)
		)
		(property "License" "Apache-2.0"
			(at 162.56 218.44 0)
			(effects
				(font
					(size 1.27 1.27)
					(thickness 0.15)
				)
				(justify left bottom)
				(hide yes)
			)
		)
		(pin "1"
		)
		(instances
			(project "polarfire-som"
				(path ""
					(reference "#PWR0117")
					(unit 1)
				)
			)
		)
	)
	(symbol
		(lib_id "antmicropower:GND")
		(at 176.53 217.17 0)
		(unit 1)
		(exclude_from_sim no)
		(in_bom yes)
		(on_board yes)
		(dnp no)
		(property "Reference" "#PWR0285"
			(at 185.42 219.71 0)
			(effects
				(font
					(size 1.27 1.27)
					(thickness 0.15)
				)
				(justify left bottom)
				(hide yes)
			)
		)
		(property "Value" "GND"
			(at 176.53 221.615 0)
			(effects
				(font
					(size 1.27 1.27)
					(thickness 0.15)
				)
			)
		)
		(property "Footprint" ""
			(at 185.42 224.79 0)
			(effects
				(font
					(size 1.27 1.27)
					(thickness 0.15)
				)
				(justify left bottom)
				(hide yes)
			)
		)
		(property "Datasheet" ""
			(at 185.42 229.87 0)
			(effects
				(font
					(size 1.27 1.27)
					(thickness 0.15)
				)
				(justify left bottom)
				(hide yes)
			)
		)
		(property "Description" ""
			(at 176.53 217.17 0)
			(effects
				(font
					(size 1.27 1.27)
				)
				(hide yes)
			)
		)
		(property "Author" "Antmicro"
			(at 185.42 224.79 0)
			(effects
				(font
					(size 1.27 1.27)
					(thickness 0.15)
				)
				(justify left bottom)
				(hide yes)
			)
		)
		(property "License" "Apache-2.0"
			(at 185.42 227.33 0)
			(effects
				(font
					(size 1.27 1.27)
					(thickness 0.15)
				)
				(justify left bottom)
				(hide yes)
			)
		)
		(pin "1"
		)
		(instances
			(project "polarfire-som"
				(path ""
					(reference "#PWR0285")
					(unit 1)
				)
			)
		)
	)
	(symbol
		(lib_id "antmicropower:GND")
		(at 176.53 195.58 0)
		(unit 1)
		(exclude_from_sim no)
		(in_bom yes)
		(on_board yes)
		(dnp no)
		(property "Reference" "#PWR0131"
			(at 185.42 198.12 0)
			(effects
				(font
					(size 1.27 1.27)
					(thickness 0.15)
				)
				(justify left bottom)
				(hide yes)
			)
		)
		(property "Value" "GND"
			(at 176.53 200.025 0)
			(effects
				(font
					(size 1.27 1.27)
					(thickness 0.15)
				)
			)
		)
		(property "Footprint" ""
			(at 185.42 203.2 0)
			(effects
				(font
					(size 1.27 1.27)
					(thickness 0.15)
				)
				(justify left bottom)
				(hide yes)
			)
		)
		(property "Datasheet" ""
			(at 185.42 208.28 0)
			(effects
				(font
					(size 1.27 1.27)
					(thickness 0.15)
				)
				(justify left bottom)
				(hide yes)
			)
		)
		(property "Description" ""
			(at 176.53 195.58 0)
			(effects
				(font
					(size 1.27 1.27)
				)
				(hide yes)
			)
		)
		(property "Author" "Antmicro"
			(at 185.42 203.2 0)
			(effects
				(font
					(size 1.27 1.27)
					(thickness 0.15)
				)
				(justify left bottom)
				(hide yes)
			)
		)
		(property "License" "Apache-2.0"
			(at 185.42 205.74 0)
			(effects
				(font
					(size 1.27 1.27)
					(thickness 0.15)
				)
				(justify left bottom)
				(hide yes)
			)
		)
		(pin "1"
		)
		(instances
			(project "polarfire-som"
				(path ""
					(reference "#PWR0131")
					(unit 1)
				)
			)
		)
	)
	(symbol
		(lib_id "antmicropower:+1V8")
		(at 130.81 185.42 0)
		(unit 1)
		(exclude_from_sim no)
		(in_bom yes)
		(on_board yes)
		(dnp no)
		(property "Reference" "#PWR0128"
			(at 146.05 187.96 0)
			(effects
				(font
					(size 1.27 1.27)
					(thickness 0.15)
				)
				(justify left bottom)
				(hide yes)
			)
		)
		(property "Value" "+1V8"
			(at 130.81 181.61 0)
			(effects
				(font
					(size 1.27 1.27)
					(thickness 0.15)
				)
			)
		)
		(property "Footprint" ""
			(at 146.05 193.04 0)
			(effects
				(font
					(size 1.27 1.27)
					(thickness 0.15)
				)
				(justify left bottom)
				(hide yes)
			)
		)
		(property "Datasheet" ""
			(at 146.05 195.58 0)
			(effects
				(font
					(size 1.27 1.27)
					(thickness 0.15)
				)
				(justify left bottom)
				(hide yes)
			)
		)
		(property "Description" ""
			(at 130.81 185.42 0)
			(effects
				(font
					(size 1.27 1.27)
				)
				(hide yes)
			)
		)
		(property "Author" "Antmicro"
			(at 146.05 193.04 0)
			(effects
				(font
					(size 1.27 1.27)
					(thickness 0.15)
				)
				(justify left bottom)
				(hide yes)
			)
		)
		(property "License" "Apache-2.0"
			(at 146.05 195.58 0)
			(effects
				(font
					(size 1.27 1.27)
					(thickness 0.15)
				)
				(justify left bottom)
				(hide yes)
			)
		)
		(pin "1"
		)
		(instances
			(project "polarfire-som"
				(path ""
					(reference "#PWR0128")
					(unit 1)
				)
			)
		)
	)
	(symbol
		(lib_id "antmicroCapacitors0402:C_1u_0402")
		(at 212.09 194.31 90)
		(unit 1)
		(exclude_from_sim no)
		(in_bom yes)
		(on_board yes)
		(dnp no)
		(property "Reference" "C147"
			(at 213.36 189.23 90)
			(effects
				(font
					(size 1.27 1.27)
					(thickness 0.15)
				)
				(justify right bottom)
			)
		)
		(property "Value" "C_1u_0402"
			(at 222.25 173.99 0)
			(effects
				(font
					(size 1.27 1.27)
					(thickness 0.15)
				)
				(justify left bottom)
				(hide yes)
			)
		)
		(property "Footprint" "antmicro-footprints:C_0402_1005Metric"
			(at 224.79 173.99 0)
			(effects
				(font
					(size 1.27 1.27)
					(thickness 0.15)
				)
				(justify left bottom)
				(hide yes)
			)
		)
		(property "Datasheet" "https://product.tdk.com/en/search/capacitor/ceramic/mlcc/info?part_no=C1005X6S1A105K050BC"
			(at 227.33 173.99 0)
			(effects
				(font
					(size 1.27 1.27)
					(thickness 0.15)
				)
				(justify left bottom)
				(hide yes)
			)
		)
		(property "Description" "SMD Multilayer Ceramic Capacitor, 1 µF, 10 V, 0402 [1005 Metric], ± 10%, X6S, C"
			(at 212.09 194.31 0)
			(effects
				(font
					(size 1.27 1.27)
				)
				(hide yes)
			)
		)
		(property "MPN" "C1005X6S1A105K050BC"
			(at 229.87 173.99 0)
			(effects
				(font
					(size 1.27 1.27)
					(thickness 0.15)
				)
				(justify left bottom)
				(hide yes)
			)
		)
		(property "Manufacturer" "TDK"
			(at 232.41 173.99 0)
			(effects
				(font
					(size 1.27 1.27)
					(thickness 0.15)
				)
				(justify left bottom)
				(hide yes)
			)
		)
		(property "License" "Apache-2.0"
			(at 234.95 173.99 0)
			(effects
				(font
					(size 1.27 1.27)
					(thickness 0.15)
				)
				(justify left bottom)
				(hide yes)
			)
		)
		(property "Author" "Antmicro"
			(at 237.49 173.99 0)
			(effects
				(font
					(size 1.27 1.27)
					(thickness 0.15)
				)
				(justify left bottom)
				(hide yes)
			)
		)
		(property "Val" "1u"
			(at 217.17 191.77 90)
			(effects
				(font
					(size 1.27 1.27)
					(thickness 0.15)
				)
				(justify left bottom)
			)
		)
		(property "Voltage" "16V"
			(at 240.03 173.99 0)
			(effects
				(font
					(size 1.27 1.27)
				)
				(justify left bottom)
				(hide yes)
			)
		)
		(property "Dielectric" "X5R"
			(at 242.57 173.99 0)
			(effects
				(font
					(size 1.27 1.27)
				)
				(justify left bottom)
				(hide yes)
			)
		)
		(property "Public" ""
			(at 245.11 173.99 0)
			(effects
				(font
					(size 1.27 1.27)
				)
				(justify left bottom)
				(hide yes)
			)
		)
		(pin "1"
		)
		(pin "2"
		)
		(instances
			(project "polarfire-som"
				(path ""
					(reference "C147")
					(unit 1)
				)
			)
		)
	)
	(symbol
		(lib_id "antmicroCapacitors0402:C_1u_0402")
		(at 204.47 194.31 90)
		(unit 1)
		(exclude_from_sim no)
		(in_bom yes)
		(on_board yes)
		(dnp no)
		(property "Reference" "C146"
			(at 205.74 189.23 90)
			(effects
				(font
					(size 1.27 1.27)
					(thickness 0.15)
				)
				(justify right bottom)
			)
		)
		(property "Value" "C_1u_0402"
			(at 214.63 173.99 0)
			(effects
				(font
					(size 1.27 1.27)
					(thickness 0.15)
				)
				(justify left bottom)
				(hide yes)
			)
		)
		(property "Footprint" "antmicro-footprints:C_0402_1005Metric"
			(at 217.17 173.99 0)
			(effects
				(font
					(size 1.27 1.27)
					(thickness 0.15)
				)
				(justify left bottom)
				(hide yes)
			)
		)
		(property "Datasheet" "https://product.tdk.com/en/search/capacitor/ceramic/mlcc/info?part_no=C1005X6S1A105K050BC"
			(at 219.71 173.99 0)
			(effects
				(font
					(size 1.27 1.27)
					(thickness 0.15)
				)
				(justify left bottom)
				(hide yes)
			)
		)
		(property "Description" "SMD Multilayer Ceramic Capacitor, 1 µF, 10 V, 0402 [1005 Metric], ± 10%, X6S, C"
			(at 204.47 194.31 0)
			(effects
				(font
					(size 1.27 1.27)
				)
				(hide yes)
			)
		)
		(property "MPN" "C1005X6S1A105K050BC"
			(at 222.25 173.99 0)
			(effects
				(font
					(size 1.27 1.27)
					(thickness 0.15)
				)
				(justify left bottom)
				(hide yes)
			)
		)
		(property "Manufacturer" "TDK"
			(at 224.79 173.99 0)
			(effects
				(font
					(size 1.27 1.27)
					(thickness 0.15)
				)
				(justify left bottom)
				(hide yes)
			)
		)
		(property "License" "Apache-2.0"
			(at 227.33 173.99 0)
			(effects
				(font
					(size 1.27 1.27)
					(thickness 0.15)
				)
				(justify left bottom)
				(hide yes)
			)
		)
		(property "Author" "Antmicro"
			(at 229.87 173.99 0)
			(effects
				(font
					(size 1.27 1.27)
					(thickness 0.15)
				)
				(justify left bottom)
				(hide yes)
			)
		)
		(property "Val" "1u"
			(at 209.55 191.77 90)
			(effects
				(font
					(size 1.27 1.27)
					(thickness 0.15)
				)
				(justify left bottom)
			)
		)
		(property "Voltage" "16V"
			(at 232.41 173.99 0)
			(effects
				(font
					(size 1.27 1.27)
				)
				(justify left bottom)
				(hide yes)
			)
		)
		(property "Dielectric" "X5R"
			(at 234.95 173.99 0)
			(effects
				(font
					(size 1.27 1.27)
				)
				(justify left bottom)
				(hide yes)
			)
		)
		(property "Public" ""
			(at 237.49 173.99 0)
			(effects
				(font
					(size 1.27 1.27)
				)
				(justify left bottom)
				(hide yes)
			)
		)
		(pin "1"
		)
		(pin "2"
		)
		(instances
			(project "polarfire-som"
				(path ""
					(reference "C146")
					(unit 1)
				)
			)
		)
	)
	(symbol
		(lib_id "antmicroCapacitors0402:C_1u_0402")
		(at 147.32 194.31 90)
		(unit 1)
		(exclude_from_sim no)
		(in_bom yes)
		(on_board yes)
		(dnp no)
		(property "Reference" "C118"
			(at 148.59 189.23 90)
			(effects
				(font
					(size 1.27 1.27)
					(thickness 0.15)
				)
				(justify right bottom)
			)
		)
		(property "Value" "C_1u_0402"
			(at 157.48 173.99 0)
			(effects
				(font
					(size 1.27 1.27)
					(thickness 0.15)
				)
				(justify left bottom)
				(hide yes)
			)
		)
		(property "Footprint" "antmicro-footprints:C_0402_1005Metric"
			(at 160.02 173.99 0)
			(effects
				(font
					(size 1.27 1.27)
					(thickness 0.15)
				)
				(justify left bottom)
				(hide yes)
			)
		)
		(property "Datasheet" "https://product.tdk.com/en/search/capacitor/ceramic/mlcc/info?part_no=C1005X6S1A105K050BC"
			(at 162.56 173.99 0)
			(effects
				(font
					(size 1.27 1.27)
					(thickness 0.15)
				)
				(justify left bottom)
				(hide yes)
			)
		)
		(property "Description" "SMD Multilayer Ceramic Capacitor, 1 µF, 10 V, 0402 [1005 Metric], ± 10%, X6S, C"
			(at 147.32 194.31 0)
			(effects
				(font
					(size 1.27 1.27)
				)
				(hide yes)
			)
		)
		(property "MPN" "C1005X6S1A105K050BC"
			(at 165.1 173.99 0)
			(effects
				(font
					(size 1.27 1.27)
					(thickness 0.15)
				)
				(justify left bottom)
				(hide yes)
			)
		)
		(property "Manufacturer" "TDK"
			(at 167.64 173.99 0)
			(effects
				(font
					(size 1.27 1.27)
					(thickness 0.15)
				)
				(justify left bottom)
				(hide yes)
			)
		)
		(property "License" "Apache-2.0"
			(at 170.18 173.99 0)
			(effects
				(font
					(size 1.27 1.27)
					(thickness 0.15)
				)
				(justify left bottom)
				(hide yes)
			)
		)
		(property "Author" "Antmicro"
			(at 172.72 173.99 0)
			(effects
				(font
					(size 1.27 1.27)
					(thickness 0.15)
				)
				(justify left bottom)
				(hide yes)
			)
		)
		(property "Val" "1u"
			(at 152.4 191.77 90)
			(effects
				(font
					(size 1.27 1.27)
					(thickness 0.15)
				)
				(justify left bottom)
			)
		)
		(property "Voltage" "16V"
			(at 175.26 173.99 0)
			(effects
				(font
					(size 1.27 1.27)
				)
				(justify left bottom)
				(hide yes)
			)
		)
		(property "Dielectric" "X5R"
			(at 177.8 173.99 0)
			(effects
				(font
					(size 1.27 1.27)
				)
				(justify left bottom)
				(hide yes)
			)
		)
		(property "Public" ""
			(at 180.34 173.99 0)
			(effects
				(font
					(size 1.27 1.27)
				)
				(justify left bottom)
				(hide yes)
			)
		)
		(pin "1"
		)
		(pin "2"
		)
		(instances
			(project "polarfire-som"
				(path ""
					(reference "C118")
					(unit 1)
				)
			)
		)
	)
	(symbol
		(lib_id "antmicroCapacitors0402:C_1u_0402")
		(at 187.96 194.31 90)
		(unit 1)
		(exclude_from_sim no)
		(in_bom yes)
		(on_board yes)
		(dnp no)
		(property "Reference" "C144"
			(at 189.23 189.23 90)
			(effects
				(font
					(size 1.27 1.27)
					(thickness 0.15)
				)
				(justify right bottom)
			)
		)
		(property "Value" "C_1u_0402"
			(at 198.12 173.99 0)
			(effects
				(font
					(size 1.27 1.27)
					(thickness 0.15)
				)
				(justify left bottom)
				(hide yes)
			)
		)
		(property "Footprint" "antmicro-footprints:C_0402_1005Metric"
			(at 200.66 173.99 0)
			(effects
				(font
					(size 1.27 1.27)
					(thickness 0.15)
				)
				(justify left bottom)
				(hide yes)
			)
		)
		(property "Datasheet" "https://product.tdk.com/en/search/capacitor/ceramic/mlcc/info?part_no=C1005X6S1A105K050BC"
			(at 203.2 173.99 0)
			(effects
				(font
					(size 1.27 1.27)
					(thickness 0.15)
				)
				(justify left bottom)
				(hide yes)
			)
		)
		(property "Description" "SMD Multilayer Ceramic Capacitor, 1 µF, 10 V, 0402 [1005 Metric], ± 10%, X6S, C"
			(at 187.96 194.31 0)
			(effects
				(font
					(size 1.27 1.27)
				)
				(hide yes)
			)
		)
		(property "MPN" "C1005X6S1A105K050BC"
			(at 205.74 173.99 0)
			(effects
				(font
					(size 1.27 1.27)
					(thickness 0.15)
				)
				(justify left bottom)
				(hide yes)
			)
		)
		(property "Manufacturer" "TDK"
			(at 208.28 173.99 0)
			(effects
				(font
					(size 1.27 1.27)
					(thickness 0.15)
				)
				(justify left bottom)
				(hide yes)
			)
		)
		(property "License" "Apache-2.0"
			(at 210.82 173.99 0)
			(effects
				(font
					(size 1.27 1.27)
					(thickness 0.15)
				)
				(justify left bottom)
				(hide yes)
			)
		)
		(property "Author" "Antmicro"
			(at 213.36 173.99 0)
			(effects
				(font
					(size 1.27 1.27)
					(thickness 0.15)
				)
				(justify left bottom)
				(hide yes)
			)
		)
		(property "Val" "1u"
			(at 193.04 191.77 90)
			(effects
				(font
					(size 1.27 1.27)
					(thickness 0.15)
				)
				(justify left bottom)
			)
		)
		(property "Voltage" "16V"
			(at 215.9 173.99 0)
			(effects
				(font
					(size 1.27 1.27)
				)
				(justify left bottom)
				(hide yes)
			)
		)
		(property "Dielectric" "X5R"
			(at 218.44 173.99 0)
			(effects
				(font
					(size 1.27 1.27)
				)
				(justify left bottom)
				(hide yes)
			)
		)
		(property "Public" ""
			(at 220.98 173.99 0)
			(effects
				(font
					(size 1.27 1.27)
				)
				(justify left bottom)
				(hide yes)
			)
		)
		(pin "1"
		)
		(pin "2"
		)
		(instances
			(project "polarfire-som"
				(path ""
					(reference "C144")
					(unit 1)
				)
			)
		)
	)
	(symbol
		(lib_id "antmicropower:+1V8")
		(at 130.81 208.28 0)
		(unit 1)
		(exclude_from_sim no)
		(in_bom yes)
		(on_board yes)
		(dnp no)
		(property "Reference" "#PWR0293"
			(at 146.05 210.82 0)
			(effects
				(font
					(size 1.27 1.27)
					(thickness 0.15)
				)
				(justify left bottom)
				(hide yes)
			)
		)
		(property "Value" "+1V8"
			(at 130.81 204.47 0)
			(effects
				(font
					(size 1.27 1.27)
					(thickness 0.15)
				)
			)
		)
		(property "Footprint" ""
			(at 146.05 215.9 0)
			(effects
				(font
					(size 1.27 1.27)
					(thickness 0.15)
				)
				(justify left bottom)
				(hide yes)
			)
		)
		(property "Datasheet" ""
			(at 146.05 218.44 0)
			(effects
				(font
					(size 1.27 1.27)
					(thickness 0.15)
				)
				(justify left bottom)
				(hide yes)
			)
		)
		(property "Description" ""
			(at 130.81 208.28 0)
			(effects
				(font
					(size 1.27 1.27)
				)
				(hide yes)
			)
		)
		(property "Author" "Antmicro"
			(at 146.05 215.9 0)
			(effects
				(font
					(size 1.27 1.27)
					(thickness 0.15)
				)
				(justify left bottom)
				(hide yes)
			)
		)
		(property "License" "Apache-2.0"
			(at 146.05 218.44 0)
			(effects
				(font
					(size 1.27 1.27)
					(thickness 0.15)
				)
				(justify left bottom)
				(hide yes)
			)
		)
		(pin "1"
		)
		(instances
			(project "polarfire-som"
				(path ""
					(reference "#PWR0293")
					(unit 1)
				)
			)
		)
	)
	(symbol
		(lib_id "antmicropower:+1V1")
		(at 171.45 124.46 270)
		(unit 1)
		(exclude_from_sim no)
		(in_bom yes)
		(on_board yes)
		(dnp no)
		(property "Reference" "#PWR0114"
			(at 167.64 124.46 0)
			(effects
				(font
					(size 1.27 1.27)
				)
				(hide yes)
			)
		)
		(property "Value" "+1V1"
			(at 177.8 124.46 90)
			(effects
				(font
					(size 1.27 1.27)
				)
			)
		)
		(property "Footprint" ""
			(at 171.45 124.46 0)
			(effects
				(font
					(size 1.27 1.27)
				)
				(hide yes)
			)
		)
		(property "Datasheet" ""
			(at 171.45 124.46 0)
			(effects
				(font
					(size 1.27 1.27)
				)
				(hide yes)
			)
		)
		(property "Description" ""
			(at 171.45 124.46 0)
			(effects
				(font
					(size 1.27 1.27)
				)
				(hide yes)
			)
		)
		(pin "1"
		)
		(instances
			(project "polarfire-som"
				(path ""
					(reference "#PWR0114")
					(unit 1)
				)
			)
		)
	)
	(symbol
		(lib_id "antmicropower:+1V1")
		(at 247.65 186.69 0)
		(unit 1)
		(exclude_from_sim no)
		(in_bom yes)
		(on_board yes)
		(dnp no)
		(property "Reference" "#PWR0250"
			(at 247.65 190.5 0)
			(effects
				(font
					(size 1.27 1.27)
				)
				(hide yes)
			)
		)
		(property "Value" "+1V1"
			(at 247.65 182.88 0)
			(effects
				(font
					(size 1.27 1.27)
				)
			)
		)
		(property "Footprint" ""
			(at 247.65 186.69 0)
			(effects
				(font
					(size 1.27 1.27)
				)
				(hide yes)
			)
		)
		(property "Datasheet" ""
			(at 247.65 186.69 0)
			(effects
				(font
					(size 1.27 1.27)
				)
				(hide yes)
			)
		)
		(property "Description" ""
			(at 247.65 186.69 0)
			(effects
				(font
					(size 1.27 1.27)
				)
				(hide yes)
			)
		)
		(pin "1"
		)
		(instances
			(project "polarfire-som"
				(path ""
					(reference "#PWR0250")
					(unit 1)
				)
			)
		)
	)
	(symbol
		(lib_id "antmicroResistors0402:R_10k_0402")
		(at 114.3 106.68 90)
		(unit 1)
		(exclude_from_sim no)
		(in_bom yes)
		(on_board yes)
		(dnp no)
		(fields_autoplaced yes)
		(property "Reference" "R104"
			(at 116.205 102.8699 90)
			(effects
				(font
					(size 1.27 1.27)
					(thickness 0.15)
				)
				(justify right)
			)
		)
		(property "Value" "R_10k_0402"
			(at 127 86.36 0)
			(effects
				(font
					(size 1.27 1.27)
					(thickness 0.15)
				)
				(justify left bottom)
				(hide yes)
			)
		)
		(property "Footprint" "antmicro-footprints:R_0402_1005Metric"
			(at 129.54 86.36 0)
			(effects
				(font
					(size 1.27 1.27)
					(thickness 0.15)
				)
				(justify left bottom)
				(hide yes)
			)
		)
		(property "Datasheet" "https://www.bourns.com/docs/product-datasheets/cr.pdf"
			(at 132.08 86.36 0)
			(effects
				(font
					(size 1.27 1.27)
					(thickness 0.15)
				)
				(justify left bottom)
				(hide yes)
			)
		)
		(property "Description" "SMD Chip Resistor, 10 kohm, ± 1%, 62.5 mW, 0402 [1005 Metric], Thick Film, General Purpose"
			(at 114.3 106.68 0)
			(effects
				(font
					(size 1.27 1.27)
				)
				(hide yes)
			)
		)
		(property "MPN" "CR0402-FX-1002GLF"
			(at 134.62 86.36 0)
			(effects
				(font
					(size 1.27 1.27)
					(thickness 0.15)
				)
				(justify left bottom)
				(hide yes)
			)
		)
		(property "Manufacturer" "Bourns"
			(at 137.16 86.36 0)
			(effects
				(font
					(size 1.27 1.27)
					(thickness 0.15)
				)
				(justify left bottom)
				(hide yes)
			)
		)
		(property "License" "Apache-2.0"
			(at 139.7 86.36 0)
			(effects
				(font
					(size 1.27 1.27)
					(thickness 0.15)
				)
				(justify left bottom)
				(hide yes)
			)
		)
		(property "Author" "Antmicro"
			(at 142.24 86.36 0)
			(effects
				(font
					(size 1.27 1.27)
					(thickness 0.15)
				)
				(justify left bottom)
				(hide yes)
			)
		)
		(property "Val" "10k"
			(at 116.205 105.4099 90)
			(effects
				(font
					(size 1.27 1.27)
					(thickness 0.15)
				)
				(justify right)
			)
		)
		(property "Tolerance" "1%"
			(at 124.46 86.36 0)
			(effects
				(font
					(size 1.27 1.27)
				)
				(justify left bottom)
				(hide yes)
			)
		)
		(property "Public" ""
			(at 144.78 86.36 0)
			(effects
				(font
					(size 1.27 1.27)
				)
				(justify left bottom)
				(hide yes)
			)
		)
		(pin "1"
		)
		(pin "2"
		)
		(instances
			(project "polarfire-som"
				(path ""
					(reference "R104")
					(unit 1)
				)
			)
		)
	)
	(symbol
		(lib_id "antmicropower:GND")
		(at 130.81 195.58 0)
		(unit 1)
		(exclude_from_sim no)
		(in_bom yes)
		(on_board yes)
		(dnp no)
		(property "Reference" "#PWR0133"
			(at 139.7 198.12 0)
			(effects
				(font
					(size 1.27 1.27)
					(thickness 0.15)
				)
				(justify left bottom)
				(hide yes)
			)
		)
		(property "Value" "GND"
			(at 130.81 200.025 0)
			(effects
				(font
					(size 1.27 1.27)
					(thickness 0.15)
				)
			)
		)
		(property "Footprint" ""
			(at 139.7 203.2 0)
			(effects
				(font
					(size 1.27 1.27)
					(thickness 0.15)
				)
				(justify left bottom)
				(hide yes)
			)
		)
		(property "Datasheet" ""
			(at 139.7 208.28 0)
			(effects
				(font
					(size 1.27 1.27)
					(thickness 0.15)
				)
				(justify left bottom)
				(hide yes)
			)
		)
		(property "Description" ""
			(at 130.81 195.58 0)
			(effects
				(font
					(size 1.27 1.27)
				)
				(hide yes)
			)
		)
		(property "Author" "Antmicro"
			(at 139.7 203.2 0)
			(effects
				(font
					(size 1.27 1.27)
					(thickness 0.15)
				)
				(justify left bottom)
				(hide yes)
			)
		)
		(property "License" "Apache-2.0"
			(at 139.7 205.74 0)
			(effects
				(font
					(size 1.27 1.27)
					(thickness 0.15)
				)
				(justify left bottom)
				(hide yes)
			)
		)
		(pin "1"
		)
		(instances
			(project "polarfire-som"
				(path ""
					(reference "#PWR0133")
					(unit 1)
				)
			)
		)
	)
	(symbol
		(lib_id "antmicroCapacitors0402:C_1u_0402")
		(at 154.94 215.9 90)
		(unit 1)
		(exclude_from_sim no)
		(in_bom yes)
		(on_board yes)
		(dnp no)
		(property "Reference" "C121"
			(at 156.21 210.82 90)
			(effects
				(font
					(size 1.27 1.27)
					(thickness 0.15)
				)
				(justify right bottom)
			)
		)
		(property "Value" "C_1u_0402"
			(at 165.1 195.58 0)
			(effects
				(font
					(size 1.27 1.27)
					(thickness 0.15)
				)
				(justify left bottom)
				(hide yes)
			)
		)
		(property "Footprint" "antmicro-footprints:C_0402_1005Metric"
			(at 167.64 195.58 0)
			(effects
				(font
					(size 1.27 1.27)
					(thickness 0.15)
				)
				(justify left bottom)
				(hide yes)
			)
		)
		(property "Datasheet" "https://product.tdk.com/en/search/capacitor/ceramic/mlcc/info?part_no=C1005X6S1A105K050BC"
			(at 170.18 195.58 0)
			(effects
				(font
					(size 1.27 1.27)
					(thickness 0.15)
				)
				(justify left bottom)
				(hide yes)
			)
		)
		(property "Description" "SMD Multilayer Ceramic Capacitor, 1 µF, 10 V, 0402 [1005 Metric], ± 10%, X6S, C"
			(at 154.94 215.9 0)
			(effects
				(font
					(size 1.27 1.27)
				)
				(hide yes)
			)
		)
		(property "MPN" "C1005X6S1A105K050BC"
			(at 172.72 195.58 0)
			(effects
				(font
					(size 1.27 1.27)
					(thickness 0.15)
				)
				(justify left bottom)
				(hide yes)
			)
		)
		(property "Manufacturer" "TDK"
			(at 175.26 195.58 0)
			(effects
				(font
					(size 1.27 1.27)
					(thickness 0.15)
				)
				(justify left bottom)
				(hide yes)
			)
		)
		(property "License" "Apache-2.0"
			(at 177.8 195.58 0)
			(effects
				(font
					(size 1.27 1.27)
					(thickness 0.15)
				)
				(justify left bottom)
				(hide yes)
			)
		)
		(property "Author" "Antmicro"
			(at 180.34 195.58 0)
			(effects
				(font
					(size 1.27 1.27)
					(thickness 0.15)
				)
				(justify left bottom)
				(hide yes)
			)
		)
		(property "Val" "1u"
			(at 160.02 213.36 90)
			(effects
				(font
					(size 1.27 1.27)
					(thickness 0.15)
				)
				(justify left bottom)
			)
		)
		(property "Voltage" "16V"
			(at 182.88 195.58 0)
			(effects
				(font
					(size 1.27 1.27)
				)
				(justify left bottom)
				(hide yes)
			)
		)
		(property "Dielectric" "X5R"
			(at 185.42 195.58 0)
			(effects
				(font
					(size 1.27 1.27)
				)
				(justify left bottom)
				(hide yes)
			)
		)
		(property "Public" ""
			(at 187.96 195.58 0)
			(effects
				(font
					(size 1.27 1.27)
				)
				(justify left bottom)
				(hide yes)
			)
		)
		(pin "1"
		)
		(pin "2"
		)
		(instances
			(project "polarfire-som"
				(path ""
					(reference "C121")
					(unit 1)
				)
			)
		)
	)
	(symbol
		(lib_id "antmicroCapacitors0402:C_1u_0402")
		(at 147.32 234.95 90)
		(unit 1)
		(exclude_from_sim no)
		(in_bom yes)
		(on_board yes)
		(dnp no)
		(property "Reference" "C122"
			(at 148.59 229.87 90)
			(effects
				(font
					(size 1.27 1.27)
					(thickness 0.15)
				)
				(justify right bottom)
			)
		)
		(property "Value" "C_1u_0402"
			(at 157.48 214.63 0)
			(effects
				(font
					(size 1.27 1.27)
					(thickness 0.15)
				)
				(justify left bottom)
				(hide yes)
			)
		)
		(property "Footprint" "antmicro-footprints:C_0402_1005Metric"
			(at 160.02 214.63 0)
			(effects
				(font
					(size 1.27 1.27)
					(thickness 0.15)
				)
				(justify left bottom)
				(hide yes)
			)
		)
		(property "Datasheet" "https://product.tdk.com/en/search/capacitor/ceramic/mlcc/info?part_no=C1005X6S1A105K050BC"
			(at 162.56 214.63 0)
			(effects
				(font
					(size 1.27 1.27)
					(thickness 0.15)
				)
				(justify left bottom)
				(hide yes)
			)
		)
		(property "Description" "SMD Multilayer Ceramic Capacitor, 1 µF, 10 V, 0402 [1005 Metric], ± 10%, X6S, C"
			(at 147.32 234.95 0)
			(effects
				(font
					(size 1.27 1.27)
				)
				(hide yes)
			)
		)
		(property "MPN" "C1005X6S1A105K050BC"
			(at 165.1 214.63 0)
			(effects
				(font
					(size 1.27 1.27)
					(thickness 0.15)
				)
				(justify left bottom)
				(hide yes)
			)
		)
		(property "Manufacturer" "TDK"
			(at 167.64 214.63 0)
			(effects
				(font
					(size 1.27 1.27)
					(thickness 0.15)
				)
				(justify left bottom)
				(hide yes)
			)
		)
		(property "License" "Apache-2.0"
			(at 170.18 214.63 0)
			(effects
				(font
					(size 1.27 1.27)
					(thickness 0.15)
				)
				(justify left bottom)
				(hide yes)
			)
		)
		(property "Author" "Antmicro"
			(at 172.72 214.63 0)
			(effects
				(font
					(size 1.27 1.27)
					(thickness 0.15)
				)
				(justify left bottom)
				(hide yes)
			)
		)
		(property "Val" "1u"
			(at 152.4 232.41 90)
			(effects
				(font
					(size 1.27 1.27)
					(thickness 0.15)
				)
				(justify left bottom)
			)
		)
		(property "Voltage" "16V"
			(at 175.26 214.63 0)
			(effects
				(font
					(size 1.27 1.27)
				)
				(justify left bottom)
				(hide yes)
			)
		)
		(property "Dielectric" "X5R"
			(at 177.8 214.63 0)
			(effects
				(font
					(size 1.27 1.27)
				)
				(justify left bottom)
				(hide yes)
			)
		)
		(property "Public" ""
			(at 180.34 214.63 0)
			(effects
				(font
					(size 1.27 1.27)
				)
				(justify left bottom)
				(hide yes)
			)
		)
		(pin "1"
		)
		(pin "2"
		)
		(instances
			(project "polarfire-som"
				(path ""
					(reference "C122")
					(unit 1)
				)
			)
		)
	)
	(symbol
		(lib_id "antmicropower:GND")
		(at 154.94 218.44 0)
		(unit 1)
		(exclude_from_sim no)
		(in_bom yes)
		(on_board yes)
		(dnp no)
		(property "Reference" "#PWR0130"
			(at 163.83 220.98 0)
			(effects
				(font
					(size 1.27 1.27)
					(thickness 0.15)
				)
				(justify left bottom)
				(hide yes)
			)
		)
		(property "Value" "GND"
			(at 154.94 222.885 0)
			(effects
				(font
					(size 1.27 1.27)
					(thickness 0.15)
				)
			)
		)
		(property "Footprint" ""
			(at 163.83 226.06 0)
			(effects
				(font
					(size 1.27 1.27)
					(thickness 0.15)
				)
				(justify left bottom)
				(hide yes)
			)
		)
		(property "Datasheet" ""
			(at 163.83 231.14 0)
			(effects
				(font
					(size 1.27 1.27)
					(thickness 0.15)
				)
				(justify left bottom)
				(hide yes)
			)
		)
		(property "Description" ""
			(at 154.94 218.44 0)
			(effects
				(font
					(size 1.27 1.27)
				)
				(hide yes)
			)
		)
		(property "Author" "Antmicro"
			(at 163.83 226.06 0)
			(effects
				(font
					(size 1.27 1.27)
					(thickness 0.15)
				)
				(justify left bottom)
				(hide yes)
			)
		)
		(property "License" "Apache-2.0"
			(at 163.83 228.6 0)
			(effects
				(font
					(size 1.27 1.27)
					(thickness 0.15)
				)
				(justify left bottom)
				(hide yes)
			)
		)
		(pin "1"
		)
		(instances
			(project "polarfire-som"
				(path ""
					(reference "#PWR0130")
					(unit 1)
				)
			)
		)
	)
	(symbol
		(lib_id "antmicroCapacitors0402:C_1u_0402")
		(at 196.85 215.9 90)
		(unit 1)
		(exclude_from_sim no)
		(in_bom yes)
		(on_board yes)
		(dnp no)
		(property "Reference" "C127"
			(at 198.12 210.82 90)
			(effects
				(font
					(size 1.27 1.27)
					(thickness 0.15)
				)
				(justify right bottom)
			)
		)
		(property "Value" "C_1u_0402"
			(at 207.01 195.58 0)
			(effects
				(font
					(size 1.27 1.27)
					(thickness 0.15)
				)
				(justify left bottom)
				(hide yes)
			)
		)
		(property "Footprint" "antmicro-footprints:C_0402_1005Metric"
			(at 209.55 195.58 0)
			(effects
				(font
					(size 1.27 1.27)
					(thickness 0.15)
				)
				(justify left bottom)
				(hide yes)
			)
		)
		(property "Datasheet" "https://product.tdk.com/en/search/capacitor/ceramic/mlcc/info?part_no=C1005X6S1A105K050BC"
			(at 212.09 195.58 0)
			(effects
				(font
					(size 1.27 1.27)
					(thickness 0.15)
				)
				(justify left bottom)
				(hide yes)
			)
		)
		(property "Description" "SMD Multilayer Ceramic Capacitor, 1 µF, 10 V, 0402 [1005 Metric], ± 10%, X6S, C"
			(at 196.85 215.9 0)
			(effects
				(font
					(size 1.27 1.27)
				)
				(hide yes)
			)
		)
		(property "MPN" "C1005X6S1A105K050BC"
			(at 214.63 195.58 0)
			(effects
				(font
					(size 1.27 1.27)
					(thickness 0.15)
				)
				(justify left bottom)
				(hide yes)
			)
		)
		(property "Manufacturer" "TDK"
			(at 217.17 195.58 0)
			(effects
				(font
					(size 1.27 1.27)
					(thickness 0.15)
				)
				(justify left bottom)
				(hide yes)
			)
		)
		(property "License" "Apache-2.0"
			(at 219.71 195.58 0)
			(effects
				(font
					(size 1.27 1.27)
					(thickness 0.15)
				)
				(justify left bottom)
				(hide yes)
			)
		)
		(property "Author" "Antmicro"
			(at 222.25 195.58 0)
			(effects
				(font
					(size 1.27 1.27)
					(thickness 0.15)
				)
				(justify left bottom)
				(hide yes)
			)
		)
		(property "Val" "1u"
			(at 201.93 213.36 90)
			(effects
				(font
					(size 1.27 1.27)
					(thickness 0.15)
				)
				(justify left bottom)
			)
		)
		(property "Voltage" "16V"
			(at 224.79 195.58 0)
			(effects
				(font
					(size 1.27 1.27)
				)
				(justify left bottom)
				(hide yes)
			)
		)
		(property "Dielectric" "X5R"
			(at 227.33 195.58 0)
			(effects
				(font
					(size 1.27 1.27)
				)
				(justify left bottom)
				(hide yes)
			)
		)
		(property "Public" ""
			(at 229.87 195.58 0)
			(effects
				(font
					(size 1.27 1.27)
				)
				(justify left bottom)
				(hide yes)
			)
		)
		(pin "1"
		)
		(pin "2"
		)
		(instances
			(project "polarfire-som"
				(path ""
					(reference "C127")
					(unit 1)
				)
			)
		)
	)
	(symbol
		(lib_id "antmicropower:GND")
		(at 212.09 237.49 0)
		(unit 1)
		(exclude_from_sim no)
		(in_bom yes)
		(on_board yes)
		(dnp no)
		(property "Reference" "#PWR0135"
			(at 220.98 240.03 0)
			(effects
				(font
					(size 1.27 1.27)
					(thickness 0.15)
				)
				(justify left bottom)
				(hide yes)
			)
		)
		(property "Value" "GND"
			(at 212.09 241.935 0)
			(effects
				(font
					(size 1.27 1.27)
					(thickness 0.15)
				)
			)
		)
		(property "Footprint" ""
			(at 220.98 245.11 0)
			(effects
				(font
					(size 1.27 1.27)
					(thickness 0.15)
				)
				(justify left bottom)
				(hide yes)
			)
		)
		(property "Datasheet" ""
			(at 220.98 250.19 0)
			(effects
				(font
					(size 1.27 1.27)
					(thickness 0.15)
				)
				(justify left bottom)
				(hide yes)
			)
		)
		(property "Description" ""
			(at 212.09 237.49 0)
			(effects
				(font
					(size 1.27 1.27)
				)
				(hide yes)
			)
		)
		(property "Author" "Antmicro"
			(at 220.98 245.11 0)
			(effects
				(font
					(size 1.27 1.27)
					(thickness 0.15)
				)
				(justify left bottom)
				(hide yes)
			)
		)
		(property "License" "Apache-2.0"
			(at 220.98 247.65 0)
			(effects
				(font
					(size 1.27 1.27)
					(thickness 0.15)
				)
				(justify left bottom)
				(hide yes)
			)
		)
		(pin "1"
		)
		(instances
			(project "polarfire-som"
				(path ""
					(reference "#PWR0135")
					(unit 1)
				)
			)
		)
	)
	(symbol
		(lib_id "antmicroCapacitors0402:C_1u_0402")
		(at 246.38 215.9 90)
		(unit 1)
		(exclude_from_sim no)
		(in_bom yes)
		(on_board yes)
		(dnp no)
		(property "Reference" "C154"
			(at 247.65 210.82 90)
			(effects
				(font
					(size 1.27 1.27)
					(thickness 0.15)
				)
				(justify right bottom)
			)
		)
		(property "Value" "C_1u_0402"
			(at 256.54 195.58 0)
			(effects
				(font
					(size 1.27 1.27)
					(thickness 0.15)
				)
				(justify left bottom)
				(hide yes)
			)
		)
		(property "Footprint" "antmicro-footprints:C_0402_1005Metric"
			(at 259.08 195.58 0)
			(effects
				(font
					(size 1.27 1.27)
					(thickness 0.15)
				)
				(justify left bottom)
				(hide yes)
			)
		)
		(property "Datasheet" "https://product.tdk.com/en/search/capacitor/ceramic/mlcc/info?part_no=C1005X6S1A105K050BC"
			(at 261.62 195.58 0)
			(effects
				(font
					(size 1.27 1.27)
					(thickness 0.15)
				)
				(justify left bottom)
				(hide yes)
			)
		)
		(property "Description" "SMD Multilayer Ceramic Capacitor, 1 µF, 10 V, 0402 [1005 Metric], ± 10%, X6S, C"
			(at 246.38 215.9 0)
			(effects
				(font
					(size 1.27 1.27)
				)
				(hide yes)
			)
		)
		(property "MPN" "C1005X6S1A105K050BC"
			(at 264.16 195.58 0)
			(effects
				(font
					(size 1.27 1.27)
					(thickness 0.15)
				)
				(justify left bottom)
				(hide yes)
			)
		)
		(property "Manufacturer" "TDK"
			(at 266.7 195.58 0)
			(effects
				(font
					(size 1.27 1.27)
					(thickness 0.15)
				)
				(justify left bottom)
				(hide yes)
			)
		)
		(property "License" "Apache-2.0"
			(at 269.24 195.58 0)
			(effects
				(font
					(size 1.27 1.27)
					(thickness 0.15)
				)
				(justify left bottom)
				(hide yes)
			)
		)
		(property "Author" "Antmicro"
			(at 271.78 195.58 0)
			(effects
				(font
					(size 1.27 1.27)
					(thickness 0.15)
				)
				(justify left bottom)
				(hide yes)
			)
		)
		(property "Val" "1u"
			(at 251.46 213.36 90)
			(effects
				(font
					(size 1.27 1.27)
					(thickness 0.15)
				)
				(justify left bottom)
			)
		)
		(property "Voltage" "16V"
			(at 274.32 195.58 0)
			(effects
				(font
					(size 1.27 1.27)
				)
				(justify left bottom)
				(hide yes)
			)
		)
		(property "Dielectric" "X5R"
			(at 276.86 195.58 0)
			(effects
				(font
					(size 1.27 1.27)
				)
				(justify left bottom)
				(hide yes)
			)
		)
		(property "Public" ""
			(at 279.4 195.58 0)
			(effects
				(font
					(size 1.27 1.27)
				)
				(justify left bottom)
				(hide yes)
			)
		)
		(pin "1"
		)
		(pin "2"
		)
		(instances
			(project "polarfire-som"
				(path ""
					(reference "C154")
					(unit 1)
				)
			)
		)
	)
	(symbol
		(lib_id "antmicropower:+1V1")
		(at 189.23 227.33 0)
		(unit 1)
		(exclude_from_sim no)
		(in_bom yes)
		(on_board yes)
		(dnp no)
		(property "Reference" "#PWR0139"
			(at 189.23 231.14 0)
			(effects
				(font
					(size 1.27 1.27)
				)
				(hide yes)
			)
		)
		(property "Value" "+1V1"
			(at 189.23 223.52 0)
			(effects
				(font
					(size 1.27 1.27)
				)
			)
		)
		(property "Footprint" ""
			(at 189.23 227.33 0)
			(effects
				(font
					(size 1.27 1.27)
				)
				(hide yes)
			)
		)
		(property "Datasheet" ""
			(at 189.23 227.33 0)
			(effects
				(font
					(size 1.27 1.27)
				)
				(hide yes)
			)
		)
		(property "Description" ""
			(at 189.23 227.33 0)
			(effects
				(font
					(size 1.27 1.27)
				)
				(hide yes)
			)
		)
		(pin "1"
		)
		(instances
			(project "polarfire-som"
				(path ""
					(reference "#PWR0139")
					(unit 1)
				)
			)
		)
	)
	(symbol
		(lib_id "antmicroCapacitors0402:C_1u_0402")
		(at 196.85 194.31 90)
		(unit 1)
		(exclude_from_sim no)
		(in_bom yes)
		(on_board yes)
		(dnp no)
		(property "Reference" "C145"
			(at 198.12 189.23 90)
			(effects
				(font
					(size 1.27 1.27)
					(thickness 0.15)
				)
				(justify right bottom)
			)
		)
		(property "Value" "C_1u_0402"
			(at 207.01 173.99 0)
			(effects
				(font
					(size 1.27 1.27)
					(thickness 0.15)
				)
				(justify left bottom)
				(hide yes)
			)
		)
		(property "Footprint" "antmicro-footprints:C_0402_1005Metric"
			(at 209.55 173.99 0)
			(effects
				(font
					(size 1.27 1.27)
					(thickness 0.15)
				)
				(justify left bottom)
				(hide yes)
			)
		)
		(property "Datasheet" "https://product.tdk.com/en/search/capacitor/ceramic/mlcc/info?part_no=C1005X6S1A105K050BC"
			(at 212.09 173.99 0)
			(effects
				(font
					(size 1.27 1.27)
					(thickness 0.15)
				)
				(justify left bottom)
				(hide yes)
			)
		)
		(property "Description" "SMD Multilayer Ceramic Capacitor, 1 µF, 10 V, 0402 [1005 Metric], ± 10%, X6S, C"
			(at 196.85 194.31 0)
			(effects
				(font
					(size 1.27 1.27)
				)
				(hide yes)
			)
		)
		(property "MPN" "C1005X6S1A105K050BC"
			(at 214.63 173.99 0)
			(effects
				(font
					(size 1.27 1.27)
					(thickness 0.15)
				)
				(justify left bottom)
				(hide yes)
			)
		)
		(property "Manufacturer" "TDK"
			(at 217.17 173.99 0)
			(effects
				(font
					(size 1.27 1.27)
					(thickness 0.15)
				)
				(justify left bottom)
				(hide yes)
			)
		)
		(property "License" "Apache-2.0"
			(at 219.71 173.99 0)
			(effects
				(font
					(size 1.27 1.27)
					(thickness 0.15)
				)
				(justify left bottom)
				(hide yes)
			)
		)
		(property "Author" "Antmicro"
			(at 222.25 173.99 0)
			(effects
				(font
					(size 1.27 1.27)
					(thickness 0.15)
				)
				(justify left bottom)
				(hide yes)
			)
		)
		(property "Val" "1u"
			(at 201.93 191.77 90)
			(effects
				(font
					(size 1.27 1.27)
					(thickness 0.15)
				)
				(justify left bottom)
			)
		)
		(property "Voltage" "16V"
			(at 224.79 173.99 0)
			(effects
				(font
					(size 1.27 1.27)
				)
				(justify left bottom)
				(hide yes)
			)
		)
		(property "Dielectric" "X5R"
			(at 227.33 173.99 0)
			(effects
				(font
					(size 1.27 1.27)
				)
				(justify left bottom)
				(hide yes)
			)
		)
		(property "Public" ""
			(at 229.87 173.99 0)
			(effects
				(font
					(size 1.27 1.27)
				)
				(justify left bottom)
				(hide yes)
			)
		)
		(pin "1"
		)
		(pin "2"
		)
		(instances
			(project "polarfire-som"
				(path ""
					(reference "C145")
					(unit 1)
				)
			)
		)
	)
	(symbol
		(lib_id "antmicropower:GND")
		(at 269.24 218.44 0)
		(unit 1)
		(exclude_from_sim no)
		(in_bom yes)
		(on_board yes)
		(dnp no)
		(property "Reference" "#PWR0253"
			(at 278.13 220.98 0)
			(effects
				(font
					(size 1.27 1.27)
					(thickness 0.15)
				)
				(justify left bottom)
				(hide yes)
			)
		)
		(property "Value" "GND"
			(at 269.24 222.885 0)
			(effects
				(font
					(size 1.27 1.27)
					(thickness 0.15)
				)
			)
		)
		(property "Footprint" ""
			(at 278.13 226.06 0)
			(effects
				(font
					(size 1.27 1.27)
					(thickness 0.15)
				)
				(justify left bottom)
				(hide yes)
			)
		)
		(property "Datasheet" ""
			(at 278.13 231.14 0)
			(effects
				(font
					(size 1.27 1.27)
					(thickness 0.15)
				)
				(justify left bottom)
				(hide yes)
			)
		)
		(property "Description" ""
			(at 269.24 218.44 0)
			(effects
				(font
					(size 1.27 1.27)
				)
				(hide yes)
			)
		)
		(property "Author" "Antmicro"
			(at 278.13 226.06 0)
			(effects
				(font
					(size 1.27 1.27)
					(thickness 0.15)
				)
				(justify left bottom)
				(hide yes)
			)
		)
		(property "License" "Apache-2.0"
			(at 278.13 228.6 0)
			(effects
				(font
					(size 1.27 1.27)
					(thickness 0.15)
				)
				(justify left bottom)
				(hide yes)
			)
		)
		(pin "1"
		)
		(instances
			(project "polarfire-som"
				(path ""
					(reference "#PWR0253")
					(unit 1)
				)
			)
		)
	)
	(symbol
		(lib_id "antmicroCapacitors0402:C_1u_0402")
		(at 247.65 194.31 90)
		(unit 1)
		(exclude_from_sim no)
		(in_bom yes)
		(on_board yes)
		(dnp no)
		(property "Reference" "C155"
			(at 248.92 189.23 90)
			(effects
				(font
					(size 1.27 1.27)
					(thickness 0.15)
				)
				(justify right bottom)
			)
		)
		(property "Value" "C_1u_0402"
			(at 257.81 173.99 0)
			(effects
				(font
					(size 1.27 1.27)
					(thickness 0.15)
				)
				(justify left bottom)
				(hide yes)
			)
		)
		(property "Footprint" "antmicro-footprints:C_0402_1005Metric"
			(at 260.35 173.99 0)
			(effects
				(font
					(size 1.27 1.27)
					(thickness 0.15)
				)
				(justify left bottom)
				(hide yes)
			)
		)
		(property "Datasheet" "https://product.tdk.com/en/search/capacitor/ceramic/mlcc/info?part_no=C1005X6S1A105K050BC"
			(at 262.89 173.99 0)
			(effects
				(font
					(size 1.27 1.27)
					(thickness 0.15)
				)
				(justify left bottom)
				(hide yes)
			)
		)
		(property "Description" "SMD Multilayer Ceramic Capacitor, 1 µF, 10 V, 0402 [1005 Metric], ± 10%, X6S, C"
			(at 247.65 194.31 0)
			(effects
				(font
					(size 1.27 1.27)
				)
				(hide yes)
			)
		)
		(property "MPN" "C1005X6S1A105K050BC"
			(at 265.43 173.99 0)
			(effects
				(font
					(size 1.27 1.27)
					(thickness 0.15)
				)
				(justify left bottom)
				(hide yes)
			)
		)
		(property "Manufacturer" "TDK"
			(at 267.97 173.99 0)
			(effects
				(font
					(size 1.27 1.27)
					(thickness 0.15)
				)
				(justify left bottom)
				(hide yes)
			)
		)
		(property "License" "Apache-2.0"
			(at 270.51 173.99 0)
			(effects
				(font
					(size 1.27 1.27)
					(thickness 0.15)
				)
				(justify left bottom)
				(hide yes)
			)
		)
		(property "Author" "Antmicro"
			(at 273.05 173.99 0)
			(effects
				(font
					(size 1.27 1.27)
					(thickness 0.15)
				)
				(justify left bottom)
				(hide yes)
			)
		)
		(property "Val" "1u"
			(at 252.73 191.77 90)
			(effects
				(font
					(size 1.27 1.27)
					(thickness 0.15)
				)
				(justify left bottom)
			)
		)
		(property "Voltage" "16V"
			(at 275.59 173.99 0)
			(effects
				(font
					(size 1.27 1.27)
				)
				(justify left bottom)
				(hide yes)
			)
		)
		(property "Dielectric" "X5R"
			(at 278.13 173.99 0)
			(effects
				(font
					(size 1.27 1.27)
				)
				(justify left bottom)
				(hide yes)
			)
		)
		(property "Public" ""
			(at 280.67 173.99 0)
			(effects
				(font
					(size 1.27 1.27)
				)
				(justify left bottom)
				(hide yes)
			)
		)
		(pin "1"
		)
		(pin "2"
		)
		(instances
			(project "polarfire-som"
				(path ""
					(reference "C155")
					(unit 1)
				)
			)
		)
	)
	(symbol
		(lib_id "antmicropower:+1V8")
		(at 147.32 186.69 0)
		(unit 1)
		(exclude_from_sim no)
		(in_bom yes)
		(on_board yes)
		(dnp no)
		(property "Reference" "#PWR0112"
			(at 162.56 189.23 0)
			(effects
				(font
					(size 1.27 1.27)
					(thickness 0.15)
				)
				(justify left bottom)
				(hide yes)
			)
		)
		(property "Value" "+1V8"
			(at 147.32 182.88 0)
			(effects
				(font
					(size 1.27 1.27)
					(thickness 0.15)
				)
			)
		)
		(property "Footprint" ""
			(at 162.56 194.31 0)
			(effects
				(font
					(size 1.27 1.27)
					(thickness 0.15)
				)
				(justify left bottom)
				(hide yes)
			)
		)
		(property "Datasheet" ""
			(at 162.56 196.85 0)
			(effects
				(font
					(size 1.27 1.27)
					(thickness 0.15)
				)
				(justify left bottom)
				(hide yes)
			)
		)
		(property "Description" ""
			(at 147.32 186.69 0)
			(effects
				(font
					(size 1.27 1.27)
				)
				(hide yes)
			)
		)
		(property "Author" "Antmicro"
			(at 162.56 194.31 0)
			(effects
				(font
					(size 1.27 1.27)
					(thickness 0.15)
				)
				(justify left bottom)
				(hide yes)
			)
		)
		(property "License" "Apache-2.0"
			(at 162.56 196.85 0)
			(effects
				(font
					(size 1.27 1.27)
					(thickness 0.15)
				)
				(justify left bottom)
				(hide yes)
			)
		)
		(pin "1"
		)
		(instances
			(project "polarfire-som"
				(path ""
					(reference "#PWR0112")
					(unit 1)
				)
			)
		)
	)
	(symbol
		(lib_id "antmicroCapacitors0402:C_10u_0402")
		(at 130.81 193.04 90)
		(unit 1)
		(exclude_from_sim no)
		(in_bom yes)
		(on_board yes)
		(dnp no)
		(property "Reference" "C75"
			(at 132.08 187.96 90)
			(effects
				(font
					(size 1.27 1.27)
					(thickness 0.15)
				)
				(justify right bottom)
			)
		)
		(property "Value" "C_10u_0402"
			(at 140.97 172.72 0)
			(effects
				(font
					(size 1.27 1.27)
					(thickness 0.15)
				)
				(justify left bottom)
				(hide yes)
			)
		)
		(property "Footprint" "antmicro-footprints:C_0402_1005Metric"
			(at 143.51 172.72 0)
			(effects
				(font
					(size 1.27 1.27)
					(thickness 0.15)
				)
				(justify left bottom)
				(hide yes)
			)
		)
		(property "Datasheet" "https://www.yageo.com/en/Chart/Download/pdf/CC0402MRX5R5BB106"
			(at 146.05 172.72 0)
			(effects
				(font
					(size 1.27 1.27)
					(thickness 0.15)
				)
				(justify left bottom)
				(hide yes)
			)
		)
		(property "Description" "SMD Multilayer Ceramic Capacitor, 10 µF, 6.3 V, 0402 [1005 Metric], ± 20%, X5R, CC Series"
			(at 130.81 193.04 0)
			(effects
				(font
					(size 1.27 1.27)
				)
				(hide yes)
			)
		)
		(property "MPN" "CC0402MRX5R5BB106"
			(at 148.59 172.72 0)
			(effects
				(font
					(size 1.27 1.27)
					(thickness 0.15)
				)
				(justify left bottom)
				(hide yes)
			)
		)
		(property "Manufacturer" "YAGEO"
			(at 151.13 172.72 0)
			(effects
				(font
					(size 1.27 1.27)
					(thickness 0.15)
				)
				(justify left bottom)
				(hide yes)
			)
		)
		(property "License" "Apache-2.0"
			(at 153.67 172.72 0)
			(effects
				(font
					(size 1.27 1.27)
					(thickness 0.15)
				)
				(justify left bottom)
				(hide yes)
			)
		)
		(property "Author" "Antmicro"
			(at 156.21 172.72 0)
			(effects
				(font
					(size 1.27 1.27)
					(thickness 0.15)
				)
				(justify left bottom)
				(hide yes)
			)
		)
		(property "Val" "10u"
			(at 132.08 193.04 90)
			(effects
				(font
					(size 1.27 1.27)
					(thickness 0.15)
				)
				(justify right top)
			)
		)
		(property "Voltage" ""
			(at 158.75 172.72 0)
			(effects
				(font
					(size 1.27 1.27)
				)
				(justify left bottom)
				(hide yes)
			)
		)
		(property "Dielectric" ""
			(at 161.29 172.72 0)
			(effects
				(font
					(size 1.27 1.27)
				)
				(justify left bottom)
				(hide yes)
			)
		)
		(property "Public" ""
			(at 163.83 172.72 0)
			(effects
				(font
					(size 1.27 1.27)
				)
				(justify left bottom)
				(hide yes)
			)
		)
		(pin "1"
		)
		(pin "2"
		)
		(instances
			(project "polarfire-som"
				(path ""
					(reference "C75")
					(unit 1)
				)
			)
		)
	)
	(symbol
		(lib_id "antmicropower:+1V1")
		(at 219.71 54.61 0)
		(unit 1)
		(exclude_from_sim no)
		(in_bom yes)
		(on_board yes)
		(dnp no)
		(property "Reference" "#PWR0115"
			(at 219.71 58.42 0)
			(effects
				(font
					(size 1.27 1.27)
				)
				(hide yes)
			)
		)
		(property "Value" "+1V1"
			(at 219.71 50.8 0)
			(effects
				(font
					(size 1.27 1.27)
				)
			)
		)
		(property "Footprint" ""
			(at 219.71 54.61 0)
			(effects
				(font
					(size 1.27 1.27)
				)
				(hide yes)
			)
		)
		(property "Datasheet" ""
			(at 219.71 54.61 0)
			(effects
				(font
					(size 1.27 1.27)
				)
				(hide yes)
			)
		)
		(property "Description" ""
			(at 219.71 54.61 0)
			(effects
				(font
					(size 1.27 1.27)
				)
				(hide yes)
			)
		)
		(pin "1"
		)
		(instances
			(project "polarfire-som"
				(path ""
					(reference "#PWR0115")
					(unit 1)
				)
			)
		)
	)
	(symbol
		(lib_id "antmicropower:+1V8")
		(at 106.68 54.61 0)
		(unit 1)
		(exclude_from_sim no)
		(in_bom yes)
		(on_board yes)
		(dnp no)
		(property "Reference" "#PWR0126"
			(at 121.92 57.15 0)
			(effects
				(font
					(size 1.27 1.27)
					(thickness 0.15)
				)
				(justify left bottom)
				(hide yes)
			)
		)
		(property "Value" "+1V8"
			(at 106.68 50.8 0)
			(effects
				(font
					(size 1.27 1.27)
					(thickness 0.15)
				)
			)
		)
		(property "Footprint" ""
			(at 121.92 62.23 0)
			(effects
				(font
					(size 1.27 1.27)
					(thickness 0.15)
				)
				(justify left bottom)
				(hide yes)
			)
		)
		(property "Datasheet" ""
			(at 121.92 64.77 0)
			(effects
				(font
					(size 1.27 1.27)
					(thickness 0.15)
				)
				(justify left bottom)
				(hide yes)
			)
		)
		(property "Description" ""
			(at 106.68 54.61 0)
			(effects
				(font
					(size 1.27 1.27)
				)
				(hide yes)
			)
		)
		(property "Author" "Antmicro"
			(at 121.92 62.23 0)
			(effects
				(font
					(size 1.27 1.27)
					(thickness 0.15)
				)
				(justify left bottom)
				(hide yes)
			)
		)
		(property "License" "Apache-2.0"
			(at 121.92 64.77 0)
			(effects
				(font
					(size 1.27 1.27)
					(thickness 0.15)
				)
				(justify left bottom)
				(hide yes)
			)
		)
		(pin "1"
		)
		(instances
			(project "polarfire-som"
				(path ""
					(reference "#PWR0126")
					(unit 1)
				)
			)
		)
	)
	(symbol
		(lib_id "antmicroCapacitors0402:C_10u_0402")
		(at 176.53 215.9 90)
		(unit 1)
		(exclude_from_sim no)
		(in_bom yes)
		(on_board yes)
		(dnp no)
		(property "Reference" "C263"
			(at 177.8 210.82 90)
			(effects
				(font
					(size 1.27 1.27)
					(thickness 0.15)
				)
				(justify right bottom)
			)
		)
		(property "Value" "C_10u_0402"
			(at 186.69 195.58 0)
			(effects
				(font
					(size 1.27 1.27)
					(thickness 0.15)
				)
				(justify left bottom)
				(hide yes)
			)
		)
		(property "Footprint" "antmicro-footprints:C_0402_1005Metric"
			(at 189.23 195.58 0)
			(effects
				(font
					(size 1.27 1.27)
					(thickness 0.15)
				)
				(justify left bottom)
				(hide yes)
			)
		)
		(property "Datasheet" "https://www.yageo.com/en/Chart/Download/pdf/CC0402MRX5R5BB106"
			(at 191.77 195.58 0)
			(effects
				(font
					(size 1.27 1.27)
					(thickness 0.15)
				)
				(justify left bottom)
				(hide yes)
			)
		)
		(property "Description" "SMD Multilayer Ceramic Capacitor, 10 µF, 6.3 V, 0402 [1005 Metric], ± 20%, X5R, CC Series"
			(at 176.53 215.9 0)
			(effects
				(font
					(size 1.27 1.27)
				)
				(hide yes)
			)
		)
		(property "MPN" "CC0402MRX5R5BB106"
			(at 194.31 195.58 0)
			(effects
				(font
					(size 1.27 1.27)
					(thickness 0.15)
				)
				(justify left bottom)
				(hide yes)
			)
		)
		(property "Manufacturer" "YAGEO"
			(at 196.85 195.58 0)
			(effects
				(font
					(size 1.27 1.27)
					(thickness 0.15)
				)
				(justify left bottom)
				(hide yes)
			)
		)
		(property "License" "Apache-2.0"
			(at 199.39 195.58 0)
			(effects
				(font
					(size 1.27 1.27)
					(thickness 0.15)
				)
				(justify left bottom)
				(hide yes)
			)
		)
		(property "Author" "Antmicro"
			(at 201.93 195.58 0)
			(effects
				(font
					(size 1.27 1.27)
					(thickness 0.15)
				)
				(justify left bottom)
				(hide yes)
			)
		)
		(property "Val" "10u"
			(at 177.8 215.9 90)
			(effects
				(font
					(size 1.27 1.27)
					(thickness 0.15)
				)
				(justify right top)
			)
		)
		(property "Voltage" ""
			(at 204.47 195.58 0)
			(effects
				(font
					(size 1.27 1.27)
				)
				(justify left bottom)
				(hide yes)
			)
		)
		(property "Dielectric" ""
			(at 207.01 195.58 0)
			(effects
				(font
					(size 1.27 1.27)
				)
				(justify left bottom)
				(hide yes)
			)
		)
		(property "Public" ""
			(at 209.55 195.58 0)
			(effects
				(font
					(size 1.27 1.27)
				)
				(justify left bottom)
				(hide yes)
			)
		)
		(pin "1"
		)
		(pin "2"
		)
		(instances
			(project "polarfire-som"
				(path ""
					(reference "C263")
					(unit 1)
				)
			)
		)
	)
	(symbol
		(lib_id "antmicropower:+1V1")
		(at 115.57 54.61 0)
		(unit 1)
		(exclude_from_sim no)
		(in_bom yes)
		(on_board yes)
		(dnp no)
		(property "Reference" "#PWR0116"
			(at 115.57 58.42 0)
			(effects
				(font
					(size 1.27 1.27)
				)
				(hide yes)
			)
		)
		(property "Value" "+1V1"
			(at 115.57 50.8 0)
			(effects
				(font
					(size 1.27 1.27)
				)
			)
		)
		(property "Footprint" ""
			(at 115.57 54.61 0)
			(effects
				(font
					(size 1.27 1.27)
				)
				(hide yes)
			)
		)
		(property "Datasheet" ""
			(at 115.57 54.61 0)
			(effects
				(font
					(size 1.27 1.27)
				)
				(hide yes)
			)
		)
		(property "Description" ""
			(at 115.57 54.61 0)
			(effects
				(font
					(size 1.27 1.27)
				)
				(hide yes)
			)
		)
		(pin "1"
		)
		(instances
			(project "polarfire-som"
				(path ""
					(reference "#PWR0116")
					(unit 1)
				)
			)
		)
	)
	(symbol
		(lib_id "antmicropower:GND")
		(at 237.49 195.58 0)
		(unit 1)
		(exclude_from_sim no)
		(in_bom yes)
		(on_board yes)
		(dnp no)
		(property "Reference" "#PWR0292"
			(at 246.38 198.12 0)
			(effects
				(font
					(size 1.27 1.27)
					(thickness 0.15)
				)
				(justify left bottom)
				(hide yes)
			)
		)
		(property "Value" "GND"
			(at 237.49 200.025 0)
			(effects
				(font
					(size 1.27 1.27)
					(thickness 0.15)
				)
			)
		)
		(property "Footprint" ""
			(at 246.38 203.2 0)
			(effects
				(font
					(size 1.27 1.27)
					(thickness 0.15)
				)
				(justify left bottom)
				(hide yes)
			)
		)
		(property "Datasheet" ""
			(at 246.38 208.28 0)
			(effects
				(font
					(size 1.27 1.27)
					(thickness 0.15)
				)
				(justify left bottom)
				(hide yes)
			)
		)
		(property "Description" ""
			(at 237.49 195.58 0)
			(effects
				(font
					(size 1.27 1.27)
				)
				(hide yes)
			)
		)
		(property "Author" "Antmicro"
			(at 246.38 203.2 0)
			(effects
				(font
					(size 1.27 1.27)
					(thickness 0.15)
				)
				(justify left bottom)
				(hide yes)
			)
		)
		(property "License" "Apache-2.0"
			(at 246.38 205.74 0)
			(effects
				(font
					(size 1.27 1.27)
					(thickness 0.15)
				)
				(justify left bottom)
				(hide yes)
			)
		)
		(pin "1"
		)
		(instances
			(project "polarfire-som"
				(path ""
					(reference "#PWR0292")
					(unit 1)
				)
			)
		)
	)
	(symbol
		(lib_id "antmicropower:GND")
		(at 130.81 218.44 0)
		(unit 1)
		(exclude_from_sim no)
		(in_bom yes)
		(on_board yes)
		(dnp no)
		(property "Reference" "#PWR0294"
			(at 139.7 220.98 0)
			(effects
				(font
					(size 1.27 1.27)
					(thickness 0.15)
				)
				(justify left bottom)
				(hide yes)
			)
		)
		(property "Value" "GND"
			(at 130.81 222.885 0)
			(effects
				(font
					(size 1.27 1.27)
					(thickness 0.15)
				)
			)
		)
		(property "Footprint" ""
			(at 139.7 226.06 0)
			(effects
				(font
					(size 1.27 1.27)
					(thickness 0.15)
				)
				(justify left bottom)
				(hide yes)
			)
		)
		(property "Datasheet" ""
			(at 139.7 231.14 0)
			(effects
				(font
					(size 1.27 1.27)
					(thickness 0.15)
				)
				(justify left bottom)
				(hide yes)
			)
		)
		(property "Description" ""
			(at 130.81 218.44 0)
			(effects
				(font
					(size 1.27 1.27)
				)
				(hide yes)
			)
		)
		(property "Author" "Antmicro"
			(at 139.7 226.06 0)
			(effects
				(font
					(size 1.27 1.27)
					(thickness 0.15)
				)
				(justify left bottom)
				(hide yes)
			)
		)
		(property "License" "Apache-2.0"
			(at 139.7 228.6 0)
			(effects
				(font
					(size 1.27 1.27)
					(thickness 0.15)
				)
				(justify left bottom)
				(hide yes)
			)
		)
		(pin "1"
		)
		(instances
			(project "polarfire-som"
				(path ""
					(reference "#PWR0294")
					(unit 1)
				)
			)
		)
	)
	(symbol
		(lib_id "antmicropower:GND")
		(at 220.98 125.73 0)
		(unit 1)
		(exclude_from_sim no)
		(in_bom yes)
		(on_board yes)
		(dnp no)
		(fields_autoplaced yes)
		(property "Reference" "#PWR0138"
			(at 229.87 128.27 0)
			(effects
				(font
					(size 1.27 1.27)
					(thickness 0.15)
				)
				(justify left bottom)
				(hide yes)
			)
		)
		(property "Value" "GND"
			(at 220.98 130.81 0)
			(effects
				(font
					(size 1.27 1.27)
					(thickness 0.15)
				)
			)
		)
		(property "Footprint" ""
			(at 229.87 133.35 0)
			(effects
				(font
					(size 1.27 1.27)
					(thickness 0.15)
				)
				(justify left bottom)
				(hide yes)
			)
		)
		(property "Datasheet" ""
			(at 229.87 138.43 0)
			(effects
				(font
					(size 1.27 1.27)
					(thickness 0.15)
				)
				(justify left bottom)
				(hide yes)
			)
		)
		(property "Description" ""
			(at 220.98 125.73 0)
			(effects
				(font
					(size 1.27 1.27)
				)
				(hide yes)
			)
		)
		(property "Author" "Antmicro"
			(at 229.87 133.35 0)
			(effects
				(font
					(size 1.27 1.27)
					(thickness 0.15)
				)
				(justify left bottom)
				(hide yes)
			)
		)
		(property "License" "Apache-2.0"
			(at 229.87 135.89 0)
			(effects
				(font
					(size 1.27 1.27)
					(thickness 0.15)
				)
				(justify left bottom)
				(hide yes)
			)
		)
		(pin "1"
		)
		(instances
			(project "polarfire-som"
				(path ""
					(reference "#PWR0138")
					(unit 1)
				)
			)
		)
	)
	(symbol
		(lib_id "antmicropower:GND")
		(at 212.09 196.85 0)
		(unit 1)
		(exclude_from_sim no)
		(in_bom yes)
		(on_board yes)
		(dnp no)
		(property "Reference" "#PWR0137"
			(at 220.98 199.39 0)
			(effects
				(font
					(size 1.27 1.27)
					(thickness 0.15)
				)
				(justify left bottom)
				(hide yes)
			)
		)
		(property "Value" "GND"
			(at 212.09 201.295 0)
			(effects
				(font
					(size 1.27 1.27)
					(thickness 0.15)
				)
			)
		)
		(property "Footprint" ""
			(at 220.98 204.47 0)
			(effects
				(font
					(size 1.27 1.27)
					(thickness 0.15)
				)
				(justify left bottom)
				(hide yes)
			)
		)
		(property "Datasheet" ""
			(at 220.98 209.55 0)
			(effects
				(font
					(size 1.27 1.27)
					(thickness 0.15)
				)
				(justify left bottom)
				(hide yes)
			)
		)
		(property "Description" ""
			(at 212.09 196.85 0)
			(effects
				(font
					(size 1.27 1.27)
				)
				(hide yes)
			)
		)
		(property "Author" "Antmicro"
			(at 220.98 204.47 0)
			(effects
				(font
					(size 1.27 1.27)
					(thickness 0.15)
				)
				(justify left bottom)
				(hide yes)
			)
		)
		(property "License" "Apache-2.0"
			(at 220.98 207.01 0)
			(effects
				(font
					(size 1.27 1.27)
					(thickness 0.15)
				)
				(justify left bottom)
				(hide yes)
			)
		)
		(pin "1"
		)
		(instances
			(project "polarfire-som"
				(path ""
					(reference "#PWR0137")
					(unit 1)
				)
			)
		)
	)
	(symbol
		(lib_id "antmicroCapacitors0402:C_1u_0402")
		(at 154.94 194.31 90)
		(unit 1)
		(exclude_from_sim no)
		(in_bom yes)
		(on_board yes)
		(dnp no)
		(property "Reference" "C119"
			(at 156.21 189.23 90)
			(effects
				(font
					(size 1.27 1.27)
					(thickness 0.15)
				)
				(justify right bottom)
			)
		)
		(property "Value" "C_1u_0402"
			(at 165.1 173.99 0)
			(effects
				(font
					(size 1.27 1.27)
					(thickness 0.15)
				)
				(justify left bottom)
				(hide yes)
			)
		)
		(property "Footprint" "antmicro-footprints:C_0402_1005Metric"
			(at 167.64 173.99 0)
			(effects
				(font
					(size 1.27 1.27)
					(thickness 0.15)
				)
				(justify left bottom)
				(hide yes)
			)
		)
		(property "Datasheet" "https://product.tdk.com/en/search/capacitor/ceramic/mlcc/info?part_no=C1005X6S1A105K050BC"
			(at 170.18 173.99 0)
			(effects
				(font
					(size 1.27 1.27)
					(thickness 0.15)
				)
				(justify left bottom)
				(hide yes)
			)
		)
		(property "Description" "SMD Multilayer Ceramic Capacitor, 1 µF, 10 V, 0402 [1005 Metric], ± 10%, X6S, C"
			(at 154.94 194.31 0)
			(effects
				(font
					(size 1.27 1.27)
				)
				(hide yes)
			)
		)
		(property "MPN" "C1005X6S1A105K050BC"
			(at 172.72 173.99 0)
			(effects
				(font
					(size 1.27 1.27)
					(thickness 0.15)
				)
				(justify left bottom)
				(hide yes)
			)
		)
		(property "Manufacturer" "TDK"
			(at 175.26 173.99 0)
			(effects
				(font
					(size 1.27 1.27)
					(thickness 0.15)
				)
				(justify left bottom)
				(hide yes)
			)
		)
		(property "License" "Apache-2.0"
			(at 177.8 173.99 0)
			(effects
				(font
					(size 1.27 1.27)
					(thickness 0.15)
				)
				(justify left bottom)
				(hide yes)
			)
		)
		(property "Author" "Antmicro"
			(at 180.34 173.99 0)
			(effects
				(font
					(size 1.27 1.27)
					(thickness 0.15)
				)
				(justify left bottom)
				(hide yes)
			)
		)
		(property "Val" "1u"
			(at 160.02 191.77 90)
			(effects
				(font
					(size 1.27 1.27)
					(thickness 0.15)
				)
				(justify left bottom)
			)
		)
		(property "Voltage" "16V"
			(at 182.88 173.99 0)
			(effects
				(font
					(size 1.27 1.27)
				)
				(justify left bottom)
				(hide yes)
			)
		)
		(property "Dielectric" "X5R"
			(at 185.42 173.99 0)
			(effects
				(font
					(size 1.27 1.27)
				)
				(justify left bottom)
				(hide yes)
			)
		)
		(property "Public" ""
			(at 187.96 173.99 0)
			(effects
				(font
					(size 1.27 1.27)
				)
				(justify left bottom)
				(hide yes)
			)
		)
		(pin "1"
		)
		(pin "2"
		)
		(instances
			(project "polarfire-som"
				(path ""
					(reference "C119")
					(unit 1)
				)
			)
		)
	)
	(symbol
		(lib_id "antmicroCapacitors0402:C_1u_0402")
		(at 204.47 234.95 90)
		(unit 1)
		(exclude_from_sim no)
		(in_bom yes)
		(on_board yes)
		(dnp no)
		(property "Reference" "C142"
			(at 205.74 229.87 90)
			(effects
				(font
					(size 1.27 1.27)
					(thickness 0.15)
				)
				(justify right bottom)
			)
		)
		(property "Value" "C_1u_0402"
			(at 214.63 214.63 0)
			(effects
				(font
					(size 1.27 1.27)
					(thickness 0.15)
				)
				(justify left bottom)
				(hide yes)
			)
		)
		(property "Footprint" "antmicro-footprints:C_0402_1005Metric"
			(at 217.17 214.63 0)
			(effects
				(font
					(size 1.27 1.27)
					(thickness 0.15)
				)
				(justify left bottom)
				(hide yes)
			)
		)
		(property "Datasheet" "https://product.tdk.com/en/search/capacitor/ceramic/mlcc/info?part_no=C1005X6S1A105K050BC"
			(at 219.71 214.63 0)
			(effects
				(font
					(size 1.27 1.27)
					(thickness 0.15)
				)
				(justify left bottom)
				(hide yes)
			)
		)
		(property "Description" "SMD Multilayer Ceramic Capacitor, 1 µF, 10 V, 0402 [1005 Metric], ± 10%, X6S, C"
			(at 204.47 234.95 0)
			(effects
				(font
					(size 1.27 1.27)
				)
				(hide yes)
			)
		)
		(property "MPN" "C1005X6S1A105K050BC"
			(at 222.25 214.63 0)
			(effects
				(font
					(size 1.27 1.27)
					(thickness 0.15)
				)
				(justify left bottom)
				(hide yes)
			)
		)
		(property "Manufacturer" "TDK"
			(at 224.79 214.63 0)
			(effects
				(font
					(size 1.27 1.27)
					(thickness 0.15)
				)
				(justify left bottom)
				(hide yes)
			)
		)
		(property "License" "Apache-2.0"
			(at 227.33 214.63 0)
			(effects
				(font
					(size 1.27 1.27)
					(thickness 0.15)
				)
				(justify left bottom)
				(hide yes)
			)
		)
		(property "Author" "Antmicro"
			(at 229.87 214.63 0)
			(effects
				(font
					(size 1.27 1.27)
					(thickness 0.15)
				)
				(justify left bottom)
				(hide yes)
			)
		)
		(property "Val" "1u"
			(at 209.55 232.41 90)
			(effects
				(font
					(size 1.27 1.27)
					(thickness 0.15)
				)
				(justify left bottom)
			)
		)
		(property "Voltage" "16V"
			(at 232.41 214.63 0)
			(effects
				(font
					(size 1.27 1.27)
				)
				(justify left bottom)
				(hide yes)
			)
		)
		(property "Dielectric" "X5R"
			(at 234.95 214.63 0)
			(effects
				(font
					(size 1.27 1.27)
				)
				(justify left bottom)
				(hide yes)
			)
		)
		(property "Public" ""
			(at 237.49 214.63 0)
			(effects
				(font
					(size 1.27 1.27)
				)
				(justify left bottom)
				(hide yes)
			)
		)
		(pin "1"
		)
		(pin "2"
		)
		(instances
			(project "polarfire-som"
				(path ""
					(reference "C142")
					(unit 1)
				)
			)
		)
	)
	(symbol
		(lib_id "antmicropower:+1V8")
		(at 147.32 227.33 0)
		(unit 1)
		(exclude_from_sim no)
		(in_bom yes)
		(on_board yes)
		(dnp no)
		(property "Reference" "#PWR0259"
			(at 162.56 229.87 0)
			(effects
				(font
					(size 1.27 1.27)
					(thickness 0.15)
				)
				(justify left bottom)
				(hide yes)
			)
		)
		(property "Value" "+1V8"
			(at 147.32 223.52 0)
			(effects
				(font
					(size 1.27 1.27)
					(thickness 0.15)
				)
			)
		)
		(property "Footprint" ""
			(at 162.56 234.95 0)
			(effects
				(font
					(size 1.27 1.27)
					(thickness 0.15)
				)
				(justify left bottom)
				(hide yes)
			)
		)
		(property "Datasheet" ""
			(at 162.56 237.49 0)
			(effects
				(font
					(size 1.27 1.27)
					(thickness 0.15)
				)
				(justify left bottom)
				(hide yes)
			)
		)
		(property "Description" ""
			(at 147.32 227.33 0)
			(effects
				(font
					(size 1.27 1.27)
				)
				(hide yes)
			)
		)
		(property "Author" "Antmicro"
			(at 162.56 234.95 0)
			(effects
				(font
					(size 1.27 1.27)
					(thickness 0.15)
				)
				(justify left bottom)
				(hide yes)
			)
		)
		(property "License" "Apache-2.0"
			(at 162.56 237.49 0)
			(effects
				(font
					(size 1.27 1.27)
					(thickness 0.15)
				)
				(justify left bottom)
				(hide yes)
			)
		)
		(pin "1"
		)
		(instances
			(project "polarfire-som"
				(path ""
					(reference "#PWR0259")
					(unit 1)
				)
			)
		)
	)
	(symbol
		(lib_id "antmicropower:GND")
		(at 270.51 196.85 0)
		(unit 1)
		(exclude_from_sim no)
		(in_bom yes)
		(on_board yes)
		(dnp no)
		(property "Reference" "#PWR0254"
			(at 279.4 199.39 0)
			(effects
				(font
					(size 1.27 1.27)
					(thickness 0.15)
				)
				(justify left bottom)
				(hide yes)
			)
		)
		(property "Value" "GND"
			(at 270.51 201.295 0)
			(effects
				(font
					(size 1.27 1.27)
					(thickness 0.15)
				)
			)
		)
		(property "Footprint" ""
			(at 279.4 204.47 0)
			(effects
				(font
					(size 1.27 1.27)
					(thickness 0.15)
				)
				(justify left bottom)
				(hide yes)
			)
		)
		(property "Datasheet" ""
			(at 279.4 209.55 0)
			(effects
				(font
					(size 1.27 1.27)
					(thickness 0.15)
				)
				(justify left bottom)
				(hide yes)
			)
		)
		(property "Description" ""
			(at 270.51 196.85 0)
			(effects
				(font
					(size 1.27 1.27)
				)
				(hide yes)
			)
		)
		(property "Author" "Antmicro"
			(at 279.4 204.47 0)
			(effects
				(font
					(size 1.27 1.27)
					(thickness 0.15)
				)
				(justify left bottom)
				(hide yes)
			)
		)
		(property "License" "Apache-2.0"
			(at 279.4 207.01 0)
			(effects
				(font
					(size 1.27 1.27)
					(thickness 0.15)
				)
				(justify left bottom)
				(hide yes)
			)
		)
		(pin "1"
		)
		(instances
			(project "polarfire-som"
				(path ""
					(reference "#PWR0254")
					(unit 1)
				)
			)
		)
	)
	(symbol
		(lib_id "antmicroMemory:MT53D512M32D2_WFBGA")
		(at 120.65 63.5 0)
		(unit 1)
		(exclude_from_sim no)
		(in_bom yes)
		(on_board yes)
		(dnp no)
		(fields_autoplaced yes)
		(property "Reference" "U12"
			(at 137.795 55.88 0)
			(effects
				(font
					(size 1.27 1.27)
					(thickness 0.15)
				)
			)
		)
		(property "Value" "MT53D512M32D2_WFBGA"
			(at 168.91 73.66 0)
			(effects
				(font
					(size 1.27 1.27)
					(thickness 0.15)
				)
				(justify left bottom)
				(hide yes)
			)
		)
		(property "Footprint" "antmicro-footprints:BGA-200_10.0x14.5mm_Layout12x22_P0.80x0.65mm"
			(at 168.91 76.2 0)
			(effects
				(font
					(size 1.27 1.27)
					(thickness 0.15)
				)
				(justify left bottom)
				(hide yes)
			)
		)
		(property "Datasheet" "https://eu.mouser.com/datasheet/2/671/200b_z11m_non_auto_lpddr4_lpddr4x-3077547.pdf"
			(at 168.91 78.74 0)
			(effects
				(font
					(size 1.27 1.27)
					(thickness 0.15)
				)
				(justify left bottom)
				(hide yes)
			)
		)
		(property "Description" "LPDDR4 DRAM, 1GX32"
			(at 120.65 63.5 0)
			(effects
				(font
					(size 1.27 1.27)
				)
				(hide yes)
			)
		)
		(property "MPN" "MT53D512M32D2DS-053 WT:D TR"
			(at 137.795 58.42 0)
			(effects
				(font
					(size 1.27 1.27)
					(thickness 0.15)
				)
			)
		)
		(property "Manufacturer" "Micron Technology"
			(at 168.91 81.28 0)
			(effects
				(font
					(size 1.27 1.27)
					(thickness 0.15)
				)
				(justify left bottom)
				(hide yes)
			)
		)
		(property "VSD_class" "LPDDR4"
			(at 168.91 83.82 0)
			(effects
				(font
					(size 1.27 1.27)
					(thickness 0.15)
				)
				(justify left bottom)
				(hide yes)
			)
		)
		(property "Author" "Antmicro"
			(at 168.91 86.36 0)
			(effects
				(font
					(size 1.27 1.27)
					(thickness 0.15)
				)
				(justify left bottom)
				(hide yes)
			)
		)
		(property "License" "Apache-2.0"
			(at 168.91 88.9 0)
			(effects
				(font
					(size 1.27 1.27)
					(thickness 0.15)
				)
				(justify left bottom)
				(hide yes)
			)
		)
		(pin "A1"
		)
		(pin "A2"
		)
		(pin "A3"
		)
		(pin "A4"
		)
		(pin "A5"
		)
		(pin "A9"
		)
		(pin "B1"
		)
		(pin "B11"
		)
		(pin "B2"
		)
		(pin "B3"
		)
		(pin "B4"
		)
		(pin "B5"
		)
		(pin "B8"
		)
		(pin "B9"
		)
		(pin "C1"
		)
		(pin "C10"
		)
		(pin "C11"
		)
		(pin "C2"
		)
		(pin "C3"
		)
		(pin "C4"
		)
		(pin "C5"
		)
		(pin "C8"
		)
		(pin "C9"
		)
		(pin "D1"
		)
		(pin "D10"
		)
		(pin "D2"
		)
		(pin "D3"
		)
		(pin "D4"
		)
		(pin "D5"
		)
		(pin "D8"
		)
		(pin "D9"
		)
		(pin "E1"
		)
		(pin "E10"
		)
		(pin "E11"
		)
		(pin "E2"
		)
		(pin "E3"
		)
		(pin "E4"
		)
		(pin "E5"
		)
		(pin "E8"
		)
		(pin "E9"
		)
		(pin "F1"
		)
		(pin "F11"
		)
		(pin "F2"
		)
		(pin "F3"
		)
		(pin "F4"
		)
		(pin "F5"
		)
		(pin "F8"
		)
		(pin "F9"
		)
		(pin "G1"
		)
		(pin "G2"
		)
		(pin "G3"
		)
		(pin "G4"
		)
		(pin "G5"
		)
		(pin "G8"
		)
		(pin "G9"
		)
		(pin "H1"
		)
		(pin "H10"
		)
		(pin "H11"
		)
		(pin "H2"
		)
		(pin "H3"
		)
		(pin "H4"
		)
		(pin "H5"
		)
		(pin "H8"
		)
		(pin "H9"
		)
		(pin "J1"
		)
		(pin "J11"
		)
		(pin "J2"
		)
		(pin "J3"
		)
		(pin "J4"
		)
		(pin "J5"
		)
		(pin "J8"
		)
		(pin "J9"
		)
		(pin "K1"
		)
		(pin "K2"
		)
		(pin "K3"
		)
		(pin "K4"
		)
		(pin "K5"
		)
		(pin "K8"
		)
		(pin "K9"
		)
		(pin "N1"
		)
		(pin "N2"
		)
		(pin "N3"
		)
		(pin "N4"
		)
		(pin "N5"
		)
		(pin "N8"
		)
		(pin "N9"
		)
		(pin "P1"
		)
		(pin "P3"
		)
		(pin "P5"
		)
		(pin "R1"
		)
		(pin "R3"
		)
		(pin "R5"
		)
		(pin "R8"
		)
		(pin "T1"
		)
		(pin "T11"
		)
		(pin "T3"
		)
		(pin "T4"
		)
		(pin "T5"
		)
		(pin "T8"
		)
		(pin "T9"
		)
		(pin "U1"
		)
		(pin "A10"
		)
		(pin "A11"
		)
		(pin "A12"
		)
		(pin "A8"
		)
		(pin "AA1"
		)
		(pin "AA10"
		)
		(pin "AA11"
		)
		(pin "AA12"
		)
		(pin "AA2"
		)
		(pin "AA3"
		)
		(pin "AA4"
		)
		(pin "AA5"
		)
		(pin "AA8"
		)
		(pin "AA9"
		)
		(pin "AB1"
		)
		(pin "AB10"
		)
		(pin "AB11"
		)
		(pin "AB12"
		)
		(pin "AB2"
		)
		(pin "AB3"
		)
		(pin "AB4"
		)
		(pin "AB5"
		)
		(pin "AB8"
		)
		(pin "AB9"
		)
		(pin "B10"
		)
		(pin "B12"
		)
		(pin "C12"
		)
		(pin "D11"
		)
		(pin "D12"
		)
		(pin "E12"
		)
		(pin "F10"
		)
		(pin "F12"
		)
		(pin "G10"
		)
		(pin "G11"
		)
		(pin "G12"
		)
		(pin "H12"
		)
		(pin "J10"
		)
		(pin "J12"
		)
		(pin "K10"
		)
		(pin "K11"
		)
		(pin "K12"
		)
		(pin "N10"
		)
		(pin "N11"
		)
		(pin "N12"
		)
		(pin "P10"
		)
		(pin "P11"
		)
		(pin "P12"
		)
		(pin "P2"
		)
		(pin "P4"
		)
		(pin "P8"
		)
		(pin "P9"
		)
		(pin "R10"
		)
		(pin "R11"
		)
		(pin "R12"
		)
		(pin "R2"
		)
		(pin "R4"
		)
		(pin "R9"
		)
		(pin "T10"
		)
		(pin "T12"
		)
		(pin "T2"
		)
		(pin "U10"
		)
		(pin "U11"
		)
		(pin "U12"
		)
		(pin "U2"
		)
		(pin "U3"
		)
		(pin "U4"
		)
		(pin "U5"
		)
		(pin "U8"
		)
		(pin "U9"
		)
		(pin "V1"
		)
		(pin "V10"
		)
		(pin "V11"
		)
		(pin "V12"
		)
		(pin "V2"
		)
		(pin "V3"
		)
		(pin "V4"
		)
		(pin "V5"
		)
		(pin "V8"
		)
		(pin "V9"
		)
		(pin "W1"
		)
		(pin "W10"
		)
		(pin "W11"
		)
		(pin "W12"
		)
		(pin "W2"
		)
		(pin "W3"
		)
		(pin "W4"
		)
		(pin "W5"
		)
		(pin "W8"
		)
		(pin "W9"
		)
		(pin "Y1"
		)
		(pin "Y10"
		)
		(pin "Y11"
		)
		(pin "Y12"
		)
		(pin "Y2"
		)
		(pin "Y3"
		)
		(pin "Y4"
		)
		(pin "Y5"
		)
		(pin "Y8"
		)
		(pin "Y9"
		)
		(instances
			(project "polarfire-som"
				(path ""
					(reference "U12")
					(unit 1)
				)
			)
		)
	)
	(symbol
		(lib_id "antmicroCapacitors0402:C_1u_0402")
		(at 147.32 215.9 90)
		(unit 1)
		(exclude_from_sim no)
		(in_bom yes)
		(on_board yes)
		(dnp no)
		(property "Reference" "C120"
			(at 148.59 210.82 90)
			(effects
				(font
					(size 1.27 1.27)
					(thickness 0.15)
				)
				(justify right bottom)
			)
		)
		(property "Value" "C_1u_0402"
			(at 157.48 195.58 0)
			(effects
				(font
					(size 1.27 1.27)
					(thickness 0.15)
				)
				(justify left bottom)
				(hide yes)
			)
		)
		(property "Footprint" "antmicro-footprints:C_0402_1005Metric"
			(at 160.02 195.58 0)
			(effects
				(font
					(size 1.27 1.27)
					(thickness 0.15)
				)
				(justify left bottom)
				(hide yes)
			)
		)
		(property "Datasheet" "https://product.tdk.com/en/search/capacitor/ceramic/mlcc/info?part_no=C1005X6S1A105K050BC"
			(at 162.56 195.58 0)
			(effects
				(font
					(size 1.27 1.27)
					(thickness 0.15)
				)
				(justify left bottom)
				(hide yes)
			)
		)
		(property "Description" "SMD Multilayer Ceramic Capacitor, 1 µF, 10 V, 0402 [1005 Metric], ± 10%, X6S, C"
			(at 147.32 215.9 0)
			(effects
				(font
					(size 1.27 1.27)
				)
				(hide yes)
			)
		)
		(property "MPN" "C1005X6S1A105K050BC"
			(at 165.1 195.58 0)
			(effects
				(font
					(size 1.27 1.27)
					(thickness 0.15)
				)
				(justify left bottom)
				(hide yes)
			)
		)
		(property "Manufacturer" "TDK"
			(at 167.64 195.58 0)
			(effects
				(font
					(size 1.27 1.27)
					(thickness 0.15)
				)
				(justify left bottom)
				(hide yes)
			)
		)
		(property "License" "Apache-2.0"
			(at 170.18 195.58 0)
			(effects
				(font
					(size 1.27 1.27)
					(thickness 0.15)
				)
				(justify left bottom)
				(hide yes)
			)
		)
		(property "Author" "Antmicro"
			(at 172.72 195.58 0)
			(effects
				(font
					(size 1.27 1.27)
					(thickness 0.15)
				)
				(justify left bottom)
				(hide yes)
			)
		)
		(property "Val" "1u"
			(at 152.4 213.36 90)
			(effects
				(font
					(size 1.27 1.27)
					(thickness 0.15)
				)
				(justify left bottom)
			)
		)
		(property "Voltage" "16V"
			(at 175.26 195.58 0)
			(effects
				(font
					(size 1.27 1.27)
				)
				(justify left bottom)
				(hide yes)
			)
		)
		(property "Dielectric" "X5R"
			(at 177.8 195.58 0)
			(effects
				(font
					(size 1.27 1.27)
				)
				(justify left bottom)
				(hide yes)
			)
		)
		(property "Public" ""
			(at 180.34 195.58 0)
			(effects
				(font
					(size 1.27 1.27)
				)
				(justify left bottom)
				(hide yes)
			)
		)
		(pin "1"
		)
		(pin "2"
		)
		(instances
			(project "polarfire-som"
				(path ""
					(reference "C120")
					(unit 1)
				)
			)
		)
	)
	(symbol
		(lib_id "antmicroCapacitors0402:C_1u_0402")
		(at 196.85 234.95 90)
		(unit 1)
		(exclude_from_sim no)
		(in_bom yes)
		(on_board yes)
		(dnp no)
		(property "Reference" "C126"
			(at 198.12 229.87 90)
			(effects
				(font
					(size 1.27 1.27)
					(thickness 0.15)
				)
				(justify right bottom)
			)
		)
		(property "Value" "C_1u_0402"
			(at 207.01 214.63 0)
			(effects
				(font
					(size 1.27 1.27)
					(thickness 0.15)
				)
				(justify left bottom)
				(hide yes)
			)
		)
		(property "Footprint" "antmicro-footprints:C_0402_1005Metric"
			(at 209.55 214.63 0)
			(effects
				(font
					(size 1.27 1.27)
					(thickness 0.15)
				)
				(justify left bottom)
				(hide yes)
			)
		)
		(property "Datasheet" "https://product.tdk.com/en/search/capacitor/ceramic/mlcc/info?part_no=C1005X6S1A105K050BC"
			(at 212.09 214.63 0)
			(effects
				(font
					(size 1.27 1.27)
					(thickness 0.15)
				)
				(justify left bottom)
				(hide yes)
			)
		)
		(property "Description" "SMD Multilayer Ceramic Capacitor, 1 µF, 10 V, 0402 [1005 Metric], ± 10%, X6S, C"
			(at 196.85 234.95 0)
			(effects
				(font
					(size 1.27 1.27)
				)
				(hide yes)
			)
		)
		(property "MPN" "C1005X6S1A105K050BC"
			(at 214.63 214.63 0)
			(effects
				(font
					(size 1.27 1.27)
					(thickness 0.15)
				)
				(justify left bottom)
				(hide yes)
			)
		)
		(property "Manufacturer" "TDK"
			(at 217.17 214.63 0)
			(effects
				(font
					(size 1.27 1.27)
					(thickness 0.15)
				)
				(justify left bottom)
				(hide yes)
			)
		)
		(property "License" "Apache-2.0"
			(at 219.71 214.63 0)
			(effects
				(font
					(size 1.27 1.27)
					(thickness 0.15)
				)
				(justify left bottom)
				(hide yes)
			)
		)
		(property "Author" "Antmicro"
			(at 222.25 214.63 0)
			(effects
				(font
					(size 1.27 1.27)
					(thickness 0.15)
				)
				(justify left bottom)
				(hide yes)
			)
		)
		(property "Val" "1u"
			(at 201.93 232.41 90)
			(effects
				(font
					(size 1.27 1.27)
					(thickness 0.15)
				)
				(justify left bottom)
			)
		)
		(property "Voltage" "16V"
			(at 224.79 214.63 0)
			(effects
				(font
					(size 1.27 1.27)
				)
				(justify left bottom)
				(hide yes)
			)
		)
		(property "Dielectric" "X5R"
			(at 227.33 214.63 0)
			(effects
				(font
					(size 1.27 1.27)
				)
				(justify left bottom)
				(hide yes)
			)
		)
		(property "Public" ""
			(at 229.87 214.63 0)
			(effects
				(font
					(size 1.27 1.27)
				)
				(justify left bottom)
				(hide yes)
			)
		)
		(pin "1"
		)
		(pin "2"
		)
		(instances
			(project "polarfire-som"
				(path ""
					(reference "C126")
					(unit 1)
				)
			)
		)
	)
	(symbol
		(lib_id "antmicropower:GND")
		(at 114.3 107.95 0)
		(unit 1)
		(exclude_from_sim no)
		(in_bom yes)
		(on_board yes)
		(dnp no)
		(fields_autoplaced yes)
		(property "Reference" "#PWR0348"
			(at 123.19 110.49 0)
			(effects
				(font
					(size 1.27 1.27)
					(thickness 0.15)
				)
				(justify left bottom)
				(hide yes)
			)
		)
		(property "Value" "GND"
			(at 114.3 113.03 0)
			(effects
				(font
					(size 1.27 1.27)
					(thickness 0.15)
				)
			)
		)
		(property "Footprint" ""
			(at 123.19 115.57 0)
			(effects
				(font
					(size 1.27 1.27)
					(thickness 0.15)
				)
				(justify left bottom)
				(hide yes)
			)
		)
		(property "Datasheet" ""
			(at 123.19 120.65 0)
			(effects
				(font
					(size 1.27 1.27)
					(thickness 0.15)
				)
				(justify left bottom)
				(hide yes)
			)
		)
		(property "Description" ""
			(at 114.3 107.95 0)
			(effects
				(font
					(size 1.27 1.27)
				)
				(hide yes)
			)
		)
		(property "Author" "Antmicro"
			(at 123.19 115.57 0)
			(effects
				(font
					(size 1.27 1.27)
					(thickness 0.15)
				)
				(justify left bottom)
				(hide yes)
			)
		)
		(property "License" "Apache-2.0"
			(at 123.19 118.11 0)
			(effects
				(font
					(size 1.27 1.27)
					(thickness 0.15)
				)
				(justify left bottom)
				(hide yes)
			)
		)
		(pin "1"
		)
		(instances
			(project "polarfire-som"
				(path ""
					(reference "#PWR0348")
					(unit 1)
				)
			)
		)
	)
	(symbol
		(lib_id "antmicroCapacitors0402:C_1u_0402")
		(at 189.23 215.9 90)
		(unit 1)
		(exclude_from_sim no)
		(in_bom yes)
		(on_board yes)
		(dnp no)
		(property "Reference" "C128"
			(at 190.5 210.82 90)
			(effects
				(font
					(size 1.27 1.27)
					(thickness 0.15)
				)
				(justify right bottom)
			)
		)
		(property "Value" "C_1u_0402"
			(at 199.39 195.58 0)
			(effects
				(font
					(size 1.27 1.27)
					(thickness 0.15)
				)
				(justify left bottom)
				(hide yes)
			)
		)
		(property "Footprint" "antmicro-footprints:C_0402_1005Metric"
			(at 201.93 195.58 0)
			(effects
				(font
					(size 1.27 1.27)
					(thickness 0.15)
				)
				(justify left bottom)
				(hide yes)
			)
		)
		(property "Datasheet" "https://product.tdk.com/en/search/capacitor/ceramic/mlcc/info?part_no=C1005X6S1A105K050BC"
			(at 204.47 195.58 0)
			(effects
				(font
					(size 1.27 1.27)
					(thickness 0.15)
				)
				(justify left bottom)
				(hide yes)
			)
		)
		(property "Description" "SMD Multilayer Ceramic Capacitor, 1 µF, 10 V, 0402 [1005 Metric], ± 10%, X6S, C"
			(at 189.23 215.9 0)
			(effects
				(font
					(size 1.27 1.27)
				)
				(hide yes)
			)
		)
		(property "MPN" "C1005X6S1A105K050BC"
			(at 207.01 195.58 0)
			(effects
				(font
					(size 1.27 1.27)
					(thickness 0.15)
				)
				(justify left bottom)
				(hide yes)
			)
		)
		(property "Manufacturer" "TDK"
			(at 209.55 195.58 0)
			(effects
				(font
					(size 1.27 1.27)
					(thickness 0.15)
				)
				(justify left bottom)
				(hide yes)
			)
		)
		(property "License" "Apache-2.0"
			(at 212.09 195.58 0)
			(effects
				(font
					(size 1.27 1.27)
					(thickness 0.15)
				)
				(justify left bottom)
				(hide yes)
			)
		)
		(property "Author" "Antmicro"
			(at 214.63 195.58 0)
			(effects
				(font
					(size 1.27 1.27)
					(thickness 0.15)
				)
				(justify left bottom)
				(hide yes)
			)
		)
		(property "Val" "1u"
			(at 194.31 213.36 90)
			(effects
				(font
					(size 1.27 1.27)
					(thickness 0.15)
				)
				(justify left bottom)
			)
		)
		(property "Voltage" "16V"
			(at 217.17 195.58 0)
			(effects
				(font
					(size 1.27 1.27)
				)
				(justify left bottom)
				(hide yes)
			)
		)
		(property "Dielectric" "X5R"
			(at 219.71 195.58 0)
			(effects
				(font
					(size 1.27 1.27)
				)
				(justify left bottom)
				(hide yes)
			)
		)
		(property "Public" ""
			(at 222.25 195.58 0)
			(effects
				(font
					(size 1.27 1.27)
				)
				(justify left bottom)
				(hide yes)
			)
		)
		(pin "1"
		)
		(pin "2"
		)
		(instances
			(project "polarfire-som"
				(path ""
					(reference "C128")
					(unit 1)
				)
			)
		)
	)
	(symbol
		(lib_id "antmicropower:GND")
		(at 118.11 128.27 0)
		(unit 1)
		(exclude_from_sim no)
		(in_bom yes)
		(on_board yes)
		(dnp no)
		(fields_autoplaced yes)
		(property "Reference" "#PWR0127"
			(at 127 130.81 0)
			(effects
				(font
					(size 1.27 1.27)
					(thickness 0.15)
				)
				(justify left bottom)
				(hide yes)
			)
		)
		(property "Value" "GND"
			(at 118.11 133.35 0)
			(effects
				(font
					(size 1.27 1.27)
					(thickness 0.15)
				)
			)
		)
		(property "Footprint" ""
			(at 127 135.89 0)
			(effects
				(font
					(size 1.27 1.27)
					(thickness 0.15)
				)
				(justify left bottom)
				(hide yes)
			)
		)
		(property "Datasheet" ""
			(at 127 140.97 0)
			(effects
				(font
					(size 1.27 1.27)
					(thickness 0.15)
				)
				(justify left bottom)
				(hide yes)
			)
		)
		(property "Description" ""
			(at 118.11 128.27 0)
			(effects
				(font
					(size 1.27 1.27)
				)
				(hide yes)
			)
		)
		(property "Author" "Antmicro"
			(at 127 135.89 0)
			(effects
				(font
					(size 1.27 1.27)
					(thickness 0.15)
				)
				(justify left bottom)
				(hide yes)
			)
		)
		(property "License" "Apache-2.0"
			(at 127 138.43 0)
			(effects
				(font
					(size 1.27 1.27)
					(thickness 0.15)
				)
				(justify left bottom)
				(hide yes)
			)
		)
		(pin "1"
		)
		(instances
			(project "polarfire-som"
				(path ""
					(reference "#PWR0127")
					(unit 1)
				)
			)
		)
	)
)
